G04 ================== begin FILE IDENTIFICATION RECORD ==================*
G04 Layout Name:  D:/<user>/Wistron_project/16315-1/gbr/16315-1.brd*
G04 Film Name:    BSMD*
G04 File Format:  Gerber RS274X*
G04 File Origin:  Cadence Allegro 16.5-S056*
G04 Origin Date:  Fri Jun 09 15:30:18 2017*
G04 *
G04 Layer:  VIA CLASS/PASTEMASK_BOTTOM*
G04 Layer:  PIN/PASTEMASK_BOTTOM*
G04 Layer:  PACKAGE GEOMETRY/PASTEMASK_BOTTOM*
G04 Layer:  DRAWING FORMAT/LAYER_PCB_STORY*
G04 Layer:  DRAWING FORMAT/LAYER_PAST_B*
G04 Layer:  BOARD GEOMETRY/PANEL_OUTLINE*
G04 *
G04 Offset:    (0.00 0.00)*
G04 Mirror:    No*
G04 Mode:      Positive*
G04 Rotation:  0*
G04 FullContactRelief:  No*
G04 UndefLineWidth:     6.00*
G04 ================== end FILE IDENTIFICATION RECORD ====================*
%FSLAX35Y35*MOIN*%
%IR0*IPPOS*OFA0.00000B0.00000*MIA0B0*SFA1.00000B1.00000*%
%AMMACRO39*
4,1,40,.011,.007,
.011,-.007,
.010939,-.007695,
.010759,-.008368,
.010464,-.009,
.010064,-.009571,
.009571,-.010064,
.009,-.010464,
.008368,-.010759,
.007695,-.010939,
.007,-.011,
-.007,-.011,
-.007695,-.010939,
-.008368,-.010759,
-.009,-.010464,
-.009571,-.010064,
-.010064,-.009571,
-.010464,-.009,
-.010759,-.008368,
-.010939,-.007695,
-.011,-.007,
-.011,.007,
-.010939,.007695,
-.010759,.008368,
-.010464,.009,
-.010064,.009571,
-.009571,.010064,
-.009,.010464,
-.008368,.010759,
-.007695,.010939,
-.007,.011,
.007,.011,
.007695,.010939,
.008368,.010759,
.009,.010464,
.009571,.010064,
.010064,.009571,
.010464,.009,
.010759,.008368,
.010939,.007695,
.011,.007,
0.0*
%
%ADD39MACRO39*%
%AMMACRO31*
4,1,40,.013,-.017,
-.013,-.017,
-.013695,-.016939,
-.014368,-.016759,
-.015,-.016464,
-.015571,-.016064,
-.016064,-.015571,
-.016464,-.015,
-.016759,-.014368,
-.016939,-.013695,
-.017,-.013,
-.017,.013,
-.016939,.013695,
-.016759,.014368,
-.016464,.015,
-.016064,.015571,
-.015571,.016064,
-.015,.016464,
-.014368,.016759,
-.013695,.016939,
-.013,.017,
.013,.017,
.013695,.016939,
.014368,.016759,
.015,.016464,
.015571,.016064,
.016064,.015571,
.016464,.015,
.016759,.014368,
.016939,.013695,
.017,.013,
.017,-.013,
.016939,-.013695,
.016759,-.014368,
.016464,-.015,
.016064,-.015571,
.015571,-.016064,
.015,-.016464,
.014368,-.016759,
.013695,-.016939,
.013,-.017,
0.0*
%
%ADD31MACRO31*%
%AMMACRO14*
4,1,40,-.017,-.013,
-.017,.013,
-.016939,.013695,
-.016759,.014368,
-.016464,.015,
-.016064,.015571,
-.015571,.016064,
-.015,.016464,
-.014368,.016759,
-.013695,.016939,
-.013,.017,
.013,.017,
.013695,.016939,
.014368,.016759,
.015,.016464,
.015571,.016064,
.016064,.015571,
.016464,.015,
.016759,.014368,
.016939,.013695,
.017,.013,
.017,-.013,
.016939,-.013695,
.016759,-.014368,
.016464,-.015,
.016064,-.015571,
.015571,-.016064,
.015,-.016464,
.014368,-.016759,
.013695,-.016939,
.013,-.017,
-.013,-.017,
-.013695,-.016939,
-.014368,-.016759,
-.015,-.016464,
-.015571,-.016064,
-.016064,-.015571,
-.016464,-.015,
-.016759,-.014368,
-.016939,-.013695,
-.017,-.013,
0.0*
%
%ADD14MACRO14*%
%AMMACRO48*
4,1,3,-.0125,-.025,
.0125,0.0,
-.0125,.025,
-.0125,-.025,
0.0*
%
%ADD48MACRO48*%
%AMMACRO24*
4,1,3,0.0,-.0125,
.025,.0125,
-.025,.0125,
0.0,-.0125,
0.0*
%
%ADD24MACRO24*%
%ADD59R,.08X.127*%
%ADD11C,.04*%
%ADD49C,.032*%
%ADD37R,.127X.08*%
%ADD26C,.024*%
%ADD42R,.062X.062*%
%AMMACRO40*
4,1,40,.007,-.011,
-.007,-.011,
-.007695,-.010939,
-.008368,-.010759,
-.009,-.010464,
-.009571,-.010064,
-.010064,-.009571,
-.010464,-.009,
-.010759,-.008368,
-.010939,-.007695,
-.011,-.007,
-.011,.007,
-.010939,.007695,
-.010759,.008368,
-.010464,.009,
-.010064,.009571,
-.009571,.010064,
-.009,.010464,
-.008368,.010759,
-.007695,.010939,
-.007,.011,
.007,.011,
.007695,.010939,
.008368,.010759,
.009,.010464,
.009571,.010064,
.010064,.009571,
.010464,.009,
.010759,.008368,
.010939,.007695,
.011,.007,
.011,-.007,
.010939,-.007695,
.010759,-.008368,
.010464,-.009,
.010064,-.009571,
.009571,-.010064,
.009,-.010464,
.008368,-.010759,
.007695,-.010939,
.007,-.011,
0.0*
%
%ADD40MACRO40*%
%AMMACRO22*
4,1,40,-.011,-.007,
-.011,.007,
-.010939,.007695,
-.010759,.008368,
-.010464,.009,
-.010064,.009571,
-.009571,.010064,
-.009,.010464,
-.008368,.010759,
-.007695,.010939,
-.007,.011,
.007,.011,
.007695,.010939,
.008368,.010759,
.009,.010464,
.009571,.010064,
.010064,.009571,
.010464,.009,
.010759,.008368,
.010939,.007695,
.011,.007,
.011,-.007,
.010939,-.007695,
.010759,-.008368,
.010464,-.009,
.010064,-.009571,
.009571,-.010064,
.009,-.010464,
.008368,-.010759,
.007695,-.010939,
.007,-.011,
-.007,-.011,
-.007695,-.010939,
-.008368,-.010759,
-.009,-.010464,
-.009571,-.010064,
-.010064,-.009571,
-.010464,-.009,
-.010759,-.008368,
-.010939,-.007695,
-.011,-.007,
0.0*
%
%ADD22MACRO22*%
%AMMACRO33*
4,1,40,-.012,-.008,
-.012,.008,
-.011939,.008695,
-.011759,.009368,
-.011464,.01,
-.011064,.010571,
-.010571,.011064,
-.01,.011464,
-.009368,.011759,
-.008695,.011939,
-.008,.012,
.008,.012,
.008695,.011939,
.009368,.011759,
.01,.011464,
.010571,.011064,
.011064,.010571,
.011464,.01,
.011759,.009368,
.011939,.008695,
.012,.008,
.012,-.008,
.011939,-.008695,
.011759,-.009368,
.011464,-.01,
.011064,-.010571,
.010571,-.011064,
.01,-.011464,
.009368,-.011759,
.008695,-.011939,
.008,-.012,
-.008,-.012,
-.008695,-.011939,
-.009368,-.011759,
-.01,-.011464,
-.010571,-.011064,
-.011064,-.010571,
-.011464,-.01,
-.011759,-.009368,
-.011939,-.008695,
-.012,-.008,
0.0*
%
%ADD33MACRO33*%
%AMMACRO57*
4,1,40,-.008,.012,
.008,.012,
.008695,.011939,
.009368,.011759,
.01,.011464,
.010571,.011064,
.011064,.010571,
.011464,.01,
.011759,.009368,
.011939,.008695,
.012,.008,
.012,-.008,
.011939,-.008695,
.011759,-.009368,
.011464,-.01,
.011064,-.010571,
.010571,-.011064,
.01,-.011464,
.009368,-.011759,
.008695,-.011939,
.008,-.012,
-.008,-.012,
-.008695,-.011939,
-.009368,-.011759,
-.01,-.011464,
-.010571,-.011064,
-.011064,-.010571,
-.011464,-.01,
-.011759,-.009368,
-.011939,-.008695,
-.012,-.008,
-.012,.008,
-.011939,.008695,
-.011759,.009368,
-.011464,.01,
-.011064,.010571,
-.010571,.011064,
-.01,.011464,
-.009368,.011759,
-.008695,.011939,
-.008,.012,
0.0*
%
%ADD57MACRO57*%
%AMMACRO18*
4,1,40,-.013,.017,
.013,.017,
.013695,.016939,
.014368,.016759,
.015,.016464,
.015571,.016064,
.016064,.015571,
.016464,.015,
.016759,.014368,
.016939,.013695,
.017,.013,
.017,-.013,
.016939,-.013695,
.016759,-.014368,
.016464,-.015,
.016064,-.015571,
.015571,-.016064,
.015,-.016464,
.014368,-.016759,
.013695,-.016939,
.013,-.017,
-.013,-.017,
-.013695,-.016939,
-.014368,-.016759,
-.015,-.016464,
-.015571,-.016064,
-.016064,-.015571,
-.016464,-.015,
-.016759,-.014368,
-.016939,-.013695,
-.017,-.013,
-.017,.013,
-.016939,.013695,
-.016759,.014368,
-.016464,.015,
-.016064,.015571,
-.015571,.016064,
-.015,.016464,
-.014368,.016759,
-.013695,.016939,
-.013,.017,
0.0*
%
%ADD18MACRO18*%
%AMMACRO50*
4,1,40,.017,.013,
.017,-.013,
.016939,-.013695,
.016759,-.014368,
.016464,-.015,
.016064,-.015571,
.015571,-.016064,
.015,-.016464,
.014368,-.016759,
.013695,-.016939,
.013,-.017,
-.013,-.017,
-.013695,-.016939,
-.014368,-.016759,
-.015,-.016464,
-.015571,-.016064,
-.016064,-.015571,
-.016464,-.015,
-.016759,-.014368,
-.016939,-.013695,
-.017,-.013,
-.017,.013,
-.016939,.013695,
-.016759,.014368,
-.016464,.015,
-.016064,.015571,
-.015571,.016064,
-.015,.016464,
-.014368,.016759,
-.013695,.016939,
-.013,.017,
.013,.017,
.013695,.016939,
.014368,.016759,
.015,.016464,
.015571,.016064,
.016064,.015571,
.016464,.015,
.016759,.014368,
.016939,.013695,
.017,.013,
0.0*
%
%ADD50MACRO50*%
%AMMACRO41*
4,1,40,.007,-.011,
-.007,-.011,
-.007695,-.010939,
-.008368,-.010759,
-.009,-.010464,
-.009571,-.010064,
-.010064,-.009571,
-.010464,-.009,
-.010759,-.008368,
-.010939,-.007695,
-.011,-.007,
-.011,.007,
-.010939,.007695,
-.010759,.008368,
-.010464,.009,
-.010064,.009571,
-.009571,.010064,
-.009,.010464,
-.008368,.010759,
-.007695,.010939,
-.007,.011,
.007,.011,
.007695,.010939,
.008368,.010759,
.009,.010464,
.009571,.010064,
.010064,.009571,
.010464,.009,
.010759,.008368,
.010939,.007695,
.011,.007,
.011,-.007,
.010939,-.007695,
.010759,-.008368,
.010464,-.009,
.010064,-.009571,
.009571,-.010064,
.009,-.010464,
.008368,-.010759,
.007695,-.010939,
.007,-.011,
0.0*
%
%ADD41MACRO41*%
%AMMACRO23*
4,1,40,-.011,-.007,
-.011,.007,
-.010939,.007695,
-.010759,.008368,
-.010464,.009,
-.010064,.009571,
-.009571,.010064,
-.009,.010464,
-.008368,.010759,
-.007695,.010939,
-.007,.011,
.007,.011,
.007695,.010939,
.008368,.010759,
.009,.010464,
.009571,.010064,
.010064,.009571,
.010464,.009,
.010759,.008368,
.010939,.007695,
.011,.007,
.011,-.007,
.010939,-.007695,
.010759,-.008368,
.010464,-.009,
.010064,-.009571,
.009571,-.010064,
.009,-.010464,
.008368,-.010759,
.007695,-.010939,
.007,-.011,
-.007,-.011,
-.007695,-.010939,
-.008368,-.010759,
-.009,-.010464,
-.009571,-.010064,
-.010064,-.009571,
-.010464,-.009,
-.010759,-.008368,
-.010939,-.007695,
-.011,-.007,
0.0*
%
%ADD23MACRO23*%
%AMMACRO32*
4,1,40,-.012,-.008,
-.012,.008,
-.011939,.008695,
-.011759,.009368,
-.011464,.01,
-.011064,.010571,
-.010571,.011064,
-.01,.011464,
-.009368,.011759,
-.008695,.011939,
-.008,.012,
.008,.012,
.008695,.011939,
.009368,.011759,
.01,.011464,
.010571,.011064,
.011064,.010571,
.011464,.01,
.011759,.009368,
.011939,.008695,
.012,.008,
.012,-.008,
.011939,-.008695,
.011759,-.009368,
.011464,-.01,
.011064,-.010571,
.010571,-.011064,
.01,-.011464,
.009368,-.011759,
.008695,-.011939,
.008,-.012,
-.008,-.012,
-.008695,-.011939,
-.009368,-.011759,
-.01,-.011464,
-.010571,-.011064,
-.011064,-.010571,
-.011464,-.01,
-.011759,-.009368,
-.011939,-.008695,
-.012,-.008,
0.0*
%
%ADD32MACRO32*%
%AMMACRO56*
4,1,40,-.008,.012,
.008,.012,
.008695,.011939,
.009368,.011759,
.01,.011464,
.010571,.011064,
.011064,.010571,
.011464,.01,
.011759,.009368,
.011939,.008695,
.012,.008,
.012,-.008,
.011939,-.008695,
.011759,-.009368,
.011464,-.01,
.011064,-.010571,
.010571,-.011064,
.01,-.011464,
.009368,-.011759,
.008695,-.011939,
.008,-.012,
-.008,-.012,
-.008695,-.011939,
-.009368,-.011759,
-.01,-.011464,
-.010571,-.011064,
-.011064,-.010571,
-.011464,-.01,
-.011759,-.009368,
-.011939,-.008695,
-.012,-.008,
-.012,.008,
-.011939,.008695,
-.011759,.009368,
-.011464,.01,
-.011064,.010571,
-.010571,.011064,
-.01,.011464,
-.009368,.011759,
-.008695,.011939,
-.008,.012,
0.0*
%
%ADD56MACRO56*%
%AMMACRO19*
4,1,40,-.013,.017,
.013,.017,
.013695,.016939,
.014368,.016759,
.015,.016464,
.015571,.016064,
.016064,.015571,
.016464,.015,
.016759,.014368,
.016939,.013695,
.017,.013,
.017,-.013,
.016939,-.013695,
.016759,-.014368,
.016464,-.015,
.016064,-.015571,
.015571,-.016064,
.015,-.016464,
.014368,-.016759,
.013695,-.016939,
.013,-.017,
-.013,-.017,
-.013695,-.016939,
-.014368,-.016759,
-.015,-.016464,
-.015571,-.016064,
-.016064,-.015571,
-.016464,-.015,
-.016759,-.014368,
-.016939,-.013695,
-.017,-.013,
-.017,.013,
-.016939,.013695,
-.016759,.014368,
-.016464,.015,
-.016064,.015571,
-.015571,.016064,
-.015,.016464,
-.014368,.016759,
-.013695,.016939,
-.013,.017,
0.0*
%
%ADD19MACRO19*%
%AMMACRO51*
4,1,40,.017,.013,
.017,-.013,
.016939,-.013695,
.016759,-.014368,
.016464,-.015,
.016064,-.015571,
.015571,-.016064,
.015,-.016464,
.014368,-.016759,
.013695,-.016939,
.013,-.017,
-.013,-.017,
-.013695,-.016939,
-.014368,-.016759,
-.015,-.016464,
-.015571,-.016064,
-.016064,-.015571,
-.016464,-.015,
-.016759,-.014368,
-.016939,-.013695,
-.017,-.013,
-.017,.013,
-.016939,.013695,
-.016759,.014368,
-.016464,.015,
-.016064,.015571,
-.015571,.016064,
-.015,.016464,
-.014368,.016759,
-.013695,.016939,
-.013,.017,
.013,.017,
.013695,.016939,
.014368,.016759,
.015,.016464,
.015571,.016064,
.016064,.015571,
.016464,.015,
.016759,.014368,
.016939,.013695,
.017,.013,
0.0*
%
%ADD51MACRO51*%
%ADD58R,.06X.012*%
%AMMACRO25*
4,1,3,.025,-.0125,
0.0,.0125,
-.025,-.0125,
.025,-.0125,
0.0*
%
%ADD25MACRO25*%
%AMMACRO47*
4,1,3,-.0125,0.0,
.0125,-.025,
.0125,.025,
-.0125,0.0,
0.0*
%
%ADD47MACRO47*%
%ADD27R,.13X.128*%
%ADD60R,.128X.13*%
%ADD16R,.044X.012*%
%ADD62R,.012X.044*%
%ADD52R,.128X.105*%
%ADD45R,.012X.036*%
%ADD43R,.036X.012*%
%ADD46R,.012X.037*%
%ADD44R,.037X.012*%
%ADD53R,.065X.05*%
%ADD17R,.045X.055*%
%ADD12R,.055X.045*%
%ADD54R,.047X.073*%
%ADD55R,.09X.095*%
%ADD36R,.095X.09*%
%AMMACRO35*
4,1,40,.012,.008,
.012,-.008,
.011939,-.008695,
.011759,-.009368,
.011464,-.01,
.011064,-.010571,
.010571,-.011064,
.01,-.011464,
.009368,-.011759,
.008695,-.011939,
.008,-.012,
-.008,-.012,
-.008695,-.011939,
-.009368,-.011759,
-.01,-.011464,
-.010571,-.011064,
-.011064,-.010571,
-.011464,-.01,
-.011759,-.009368,
-.011939,-.008695,
-.012,-.008,
-.012,.008,
-.011939,.008695,
-.011759,.009368,
-.011464,.01,
-.011064,.010571,
-.010571,.011064,
-.01,.011464,
-.009368,.011759,
-.008695,.011939,
-.008,.012,
.008,.012,
.008695,.011939,
.009368,.011759,
.01,.011464,
.010571,.011064,
.011064,.010571,
.011464,.01,
.011759,.009368,
.011939,.008695,
.012,.008,
0.0*
%
%ADD35MACRO35*%
%AMMACRO28*
4,1,40,-.007,.011,
.007,.011,
.007695,.010939,
.008368,.010759,
.009,.010464,
.009571,.010064,
.010064,.009571,
.010464,.009,
.010759,.008368,
.010939,.007695,
.011,.007,
.011,-.007,
.010939,-.007695,
.010759,-.008368,
.010464,-.009,
.010064,-.009571,
.009571,-.010064,
.009,-.010464,
.008368,-.010759,
.007695,-.010939,
.007,-.011,
-.007,-.011,
-.007695,-.010939,
-.008368,-.010759,
-.009,-.010464,
-.009571,-.010064,
-.010064,-.009571,
-.010464,-.009,
-.010759,-.008368,
-.010939,-.007695,
-.011,-.007,
-.011,.007,
-.010939,.007695,
-.010759,.008368,
-.010464,.009,
-.010064,.009571,
-.009571,.010064,
-.009,.010464,
-.008368,.010759,
-.007695,.010939,
-.007,.011,
0.0*
%
%ADD28MACRO28*%
%AMMACRO21*
4,1,40,.008,-.012,
-.008,-.012,
-.008695,-.011939,
-.009368,-.011759,
-.01,-.011464,
-.010571,-.011064,
-.011064,-.010571,
-.011464,-.01,
-.011759,-.009368,
-.011939,-.008695,
-.012,-.008,
-.012,.008,
-.011939,.008695,
-.011759,.009368,
-.011464,.01,
-.011064,.010571,
-.010571,.011064,
-.01,.011464,
-.009368,.011759,
-.008695,.011939,
-.008,.012,
.008,.012,
.008695,.011939,
.009368,.011759,
.01,.011464,
.010571,.011064,
.011064,.010571,
.011464,.01,
.011759,.009368,
.011939,.008695,
.012,.008,
.012,-.008,
.011939,-.008695,
.011759,-.009368,
.011464,-.01,
.011064,-.010571,
.010571,-.011064,
.01,-.011464,
.009368,-.011759,
.008695,-.011939,
.008,-.012,
0.0*
%
%ADD21MACRO21*%
%AMMACRO38*
4,1,40,.011,.007,
.011,-.007,
.010939,-.007695,
.010759,-.008368,
.010464,-.009,
.010064,-.009571,
.009571,-.010064,
.009,-.010464,
.008368,-.010759,
.007695,-.010939,
.007,-.011,
-.007,-.011,
-.007695,-.010939,
-.008368,-.010759,
-.009,-.010464,
-.009571,-.010064,
-.010064,-.009571,
-.010464,-.009,
-.010759,-.008368,
-.010939,-.007695,
-.011,-.007,
-.011,.007,
-.010939,.007695,
-.010759,.008368,
-.010464,.009,
-.010064,.009571,
-.009571,.010064,
-.009,.010464,
-.008368,.010759,
-.007695,.010939,
-.007,.011,
.007,.011,
.007695,.010939,
.008368,.010759,
.009,.010464,
.009571,.010064,
.010064,.009571,
.010464,.009,
.010759,.008368,
.010939,.007695,
.011,.007,
0.0*
%
%ADD38MACRO38*%
%AMMACRO30*
4,1,40,.013,-.017,
-.013,-.017,
-.013695,-.016939,
-.014368,-.016759,
-.015,-.016464,
-.015571,-.016064,
-.016064,-.015571,
-.016464,-.015,
-.016759,-.014368,
-.016939,-.013695,
-.017,-.013,
-.017,.013,
-.016939,.013695,
-.016759,.014368,
-.016464,.015,
-.016064,.015571,
-.015571,.016064,
-.015,.016464,
-.014368,.016759,
-.013695,.016939,
-.013,.017,
.013,.017,
.013695,.016939,
.014368,.016759,
.015,.016464,
.015571,.016064,
.016064,.015571,
.016464,.015,
.016759,.014368,
.016939,.013695,
.017,.013,
.017,-.013,
.016939,-.013695,
.016759,-.014368,
.016464,-.015,
.016064,-.015571,
.015571,-.016064,
.015,-.016464,
.014368,-.016759,
.013695,-.016939,
.013,-.017,
0.0*
%
%ADD30MACRO30*%
%AMMACRO13*
4,1,40,-.017,-.013,
-.017,.013,
-.016939,.013695,
-.016759,.014368,
-.016464,.015,
-.016064,.015571,
-.015571,.016064,
-.015,.016464,
-.014368,.016759,
-.013695,.016939,
-.013,.017,
.013,.017,
.013695,.016939,
.014368,.016759,
.015,.016464,
.015571,.016064,
.016064,.015571,
.016464,.015,
.016759,.014368,
.016939,.013695,
.017,.013,
.017,-.013,
.016939,-.013695,
.016759,-.014368,
.016464,-.015,
.016064,-.015571,
.015571,-.016064,
.015,-.016464,
.014368,-.016759,
.013695,-.016939,
.013,-.017,
-.013,-.017,
-.013695,-.016939,
-.014368,-.016759,
-.015,-.016464,
-.015571,-.016064,
-.016064,-.015571,
-.016464,-.015,
-.016759,-.014368,
-.016939,-.013695,
-.017,-.013,
0.0*
%
%ADD13MACRO13*%
%AMMACRO61*
4,1,20,-.1075,.0635,
-.1075,.049,
-.118,.049,
-.118,.0395,
-.1075,.0395,
-.1075,-.0395,
-.118,-.0395,
-.118,-.049,
-.1075,-.049,
-.1075,-.0635,
.1075,-.0635,
.1075,-.049,
.118,-.049,
.118,-.0395,
.1075,-.0395,
.1075,.0395,
.118,.0395,
.118,.049,
.1075,.049,
.1075,.0635,
-.1075,.0635,
0.0*
%
%ADD61MACRO61*%
%AMMACRO15*
4,1,20,-.0635,-.1075,
-.049,-.1075,
-.049,-.118,
-.0395,-.118,
-.0395,-.1075,
.0395,-.1075,
.0395,-.118,
.049,-.118,
.049,-.1075,
.0635,-.1075,
.0635,.1075,
.049,.1075,
.049,.118,
.0395,.118,
.0395,.1075,
-.0395,.1075,
-.0395,.118,
-.049,.118,
-.049,.1075,
-.0635,.1075,
-.0635,-.1075,
0.0*
%
%ADD15MACRO15*%
%AMMACRO34*
4,1,40,.012,.008,
.012,-.008,
.011939,-.008695,
.011759,-.009368,
.011464,-.01,
.011064,-.010571,
.010571,-.011064,
.01,-.011464,
.009368,-.011759,
.008695,-.011939,
.008,-.012,
-.008,-.012,
-.008695,-.011939,
-.009368,-.011759,
-.01,-.011464,
-.010571,-.011064,
-.011064,-.010571,
-.011464,-.01,
-.011759,-.009368,
-.011939,-.008695,
-.012,-.008,
-.012,.008,
-.011939,.008695,
-.011759,.009368,
-.011464,.01,
-.011064,.010571,
-.010571,.011064,
-.01,.011464,
-.009368,.011759,
-.008695,.011939,
-.008,.012,
.008,.012,
.008695,.011939,
.009368,.011759,
.01,.011464,
.010571,.011064,
.011064,.010571,
.011464,.01,
.011759,.009368,
.011939,.008695,
.012,.008,
0.0*
%
%ADD34MACRO34*%
%AMMACRO29*
4,1,40,-.007,.011,
.007,.011,
.007695,.010939,
.008368,.010759,
.009,.010464,
.009571,.010064,
.010064,.009571,
.010464,.009,
.010759,.008368,
.010939,.007695,
.011,.007,
.011,-.007,
.010939,-.007695,
.010759,-.008368,
.010464,-.009,
.010064,-.009571,
.009571,-.010064,
.009,-.010464,
.008368,-.010759,
.007695,-.010939,
.007,-.011,
-.007,-.011,
-.007695,-.010939,
-.008368,-.010759,
-.009,-.010464,
-.009571,-.010064,
-.010064,-.009571,
-.010464,-.009,
-.010759,-.008368,
-.010939,-.007695,
-.011,-.007,
-.011,.007,
-.010939,.007695,
-.010759,.008368,
-.010464,.009,
-.010064,.009571,
-.009571,.010064,
-.009,.010464,
-.008368,.010759,
-.007695,.010939,
-.007,.011,
0.0*
%
%ADD29MACRO29*%
%AMMACRO20*
4,1,40,.008,-.012,
-.008,-.012,
-.008695,-.011939,
-.009368,-.011759,
-.01,-.011464,
-.010571,-.011064,
-.011064,-.010571,
-.011464,-.01,
-.011759,-.009368,
-.011939,-.008695,
-.012,-.008,
-.012,.008,
-.011939,.008695,
-.011759,.009368,
-.011464,.01,
-.011064,.010571,
-.010571,.011064,
-.01,.011464,
-.009368,.011759,
-.008695,.011939,
-.008,.012,
.008,.012,
.008695,.011939,
.009368,.011759,
.01,.011464,
.010571,.011064,
.011064,.010571,
.011464,.01,
.011759,.009368,
.011939,.008695,
.012,.008,
.012,-.008,
.011939,-.008695,
.011759,-.009368,
.011464,-.01,
.011064,-.010571,
.010571,-.011064,
.01,-.011464,
.009368,-.011759,
.008695,-.011939,
.008,-.012,
0.0*
%
%ADD20MACRO20*%
%ADD63C,.02*%
%ADD64C,.006*%
G75*
%LPD*%
G75*
G36*
G01X44296Y882702D02*
G03Y882652I-12800J-25D01*
G01X39896D01*
G02Y882702I-8400J25D01*
G01X44296D01*
G37*
G36*
G01X181107Y646482D02*
G03Y646432I-12800J-25D01*
G01X176707D01*
G02Y646482I-8400J25D01*
G01X181107D01*
G37*
G36*
G01X673036D02*
G03Y646432I-12800J-25D01*
G01X668636D01*
G02Y646482I-8400J25D01*
G01X673036D01*
G37*
G36*
G01X730910Y820891D02*
G03Y820841I-12800J-25D01*
G01X726510D01*
G02Y820891I-8400J25D01*
G01X730910D01*
G37*
G36*
G01X1378942Y646482D02*
G03Y646432I-12800J-25D01*
G01X1374542D01*
G02Y646482I-8400J25D01*
G01X1378942D01*
G37*
G36*
G01X1475792Y866954D02*
G03Y866904I-12800J-25D01*
G01X1471392D01*
G02Y866954I-8400J25D01*
G01X1475792D01*
G37*
G36*
G01X1615556Y646482D02*
G03Y646432I-12800J-25D01*
G01X1611156D01*
G02Y646482I-8400J25D01*
G01X1615556D01*
G37*
G36*
G01X1916146Y803962D02*
G03Y803912I-12800J-25D01*
G01X1911746D01*
G02Y803962I-8400J25D01*
G01X1916146D01*
G37*
G54D20*
X93100Y971000D03*
X159800Y559000D03*
X741883Y865289D03*
X703883Y911889D03*
X707332Y939902D03*
X750968Y896298D03*
X961000Y1516900D03*
X1733218Y991829D03*
X1891877Y877003D03*
G54D11*
X35506Y-110687D03*
X63128Y89671D03*
X60754Y1316385D03*
X72380Y1596505D03*
X1861177Y91072D03*
X1874818Y-110232D03*
G54D30*
X135026Y997741D03*
X201726Y585741D03*
X754304Y864973D03*
X1776826Y1009741D03*
X1902159Y905750D03*
G54D21*
X93100Y974600D03*
X159800Y562600D03*
X741883Y868889D03*
X703883Y915489D03*
X707332Y943502D03*
X750968Y899898D03*
X961000Y1520500D03*
X1733218Y995429D03*
X1891877Y880603D03*
G54D12*
X63500Y975500D03*
Y967900D03*
X71500Y967800D03*
Y975400D03*
X79300Y967800D03*
Y975400D03*
X87100Y967800D03*
Y975400D03*
X138200Y555800D03*
Y563400D03*
X146000Y555800D03*
Y563400D03*
X153800Y555800D03*
Y563400D03*
X205400Y989100D03*
Y996700D03*
X213200Y989100D03*
Y996700D03*
X221000Y989100D03*
Y996700D03*
X272100Y577100D03*
Y584700D03*
X279900Y577100D03*
Y584700D03*
X287700Y577100D03*
Y584700D03*
X701782Y929902D03*
Y922302D03*
X712898Y938082D03*
X720798D03*
X728698D03*
X712898Y945682D03*
X720798D03*
X728698D03*
X764418Y895398D03*
Y902998D03*
X756618Y895398D03*
Y902998D03*
X1703183Y996313D03*
Y988713D03*
X1711618Y988629D03*
Y996229D03*
X1719418Y988629D03*
Y996229D03*
X1727218Y988629D03*
Y996229D03*
X1847200Y990500D03*
Y998100D03*
X1855000Y990500D03*
Y998100D03*
X1862800Y990500D03*
Y998100D03*
X1882801Y937996D03*
Y945596D03*
G54D13*
X63463Y987125D03*
X129763Y560525D03*
X156941Y998444D03*
X223641Y586444D03*
X1702761Y1009647D03*
X1798741Y1010444D03*
G54D22*
X119741Y999116D03*
X151536Y997374D03*
X218236Y585374D03*
X186441Y587116D03*
X737984Y868796D03*
X852500Y487900D03*
X861900Y487800D03*
X1761541Y1011116D03*
X1793336Y1009374D03*
X1906500Y890200D03*
X1896943Y900950D03*
X1905943D03*
X1892500Y890700D03*
X1884500Y909200D03*
G54D40*
X745983Y864989D03*
X714054Y876958D03*
X738282Y904102D03*
X859600Y458600D03*
X967800Y1516700D03*
Y1520700D03*
X1896800Y933500D03*
Y929000D03*
G54D31*
X140626Y997741D03*
X207326Y585741D03*
X759904Y864973D03*
X1782426Y1009741D03*
X1907759Y905750D03*
G54D32*
X125263Y1001725D03*
X191963Y589725D03*
X1767063Y1013725D03*
X1847200Y904000D03*
X1864700Y936500D03*
G54D23*
X119741Y995716D03*
X151536Y993974D03*
X218236Y581974D03*
X186441Y583716D03*
X737984Y865396D03*
X852500Y484500D03*
X861900Y484400D03*
X1761541Y1007716D03*
X1793336Y1005974D03*
X1892500Y887300D03*
X1906500Y886800D03*
X1896943Y897550D03*
X1905943D03*
X1884500Y905800D03*
G54D41*
X749383Y864989D03*
X717454Y876958D03*
X741682Y904102D03*
X863000Y458600D03*
X971200Y1516700D03*
Y1520700D03*
X1900200Y933500D03*
Y929000D03*
G54D50*
X733582Y862826D03*
X718552Y887720D03*
X746183Y905889D03*
X756717Y876889D03*
X751711Y876917D03*
X1876271Y936966D03*
X1888000Y895200D03*
G54D14*
X63463Y981525D03*
X129763Y554925D03*
X156941Y992844D03*
X223641Y580844D03*
X1702761Y1004047D03*
X1798741Y1004844D03*
G54D15*
X115800Y979200D03*
X182500Y567200D03*
X1757600Y991200D03*
G54D60*
X1857176Y858948D03*
Y893570D03*
G54D51*
X733582Y868426D03*
X746183Y911489D03*
X718552Y893320D03*
X756717Y882489D03*
X751711Y882517D03*
X1888000Y900800D03*
X1876271Y942566D03*
G54D33*
X128863Y1001725D03*
X195563Y589725D03*
X1770663Y1013725D03*
X1850800Y904000D03*
X1868300Y936500D03*
G54D42*
X730882Y888502D03*
G54D24*
X114000Y998650D03*
X180700Y586650D03*
X1755800Y1010650D03*
G54D34*
X154856Y1002801D03*
X221556Y590801D03*
X749461Y868854D03*
X726225Y873544D03*
X1796656Y1014801D03*
X1850800Y907500D03*
G54D61*
X1868276Y916059D03*
G54D43*
X736988Y885549D03*
X724776D03*
X736988Y891455D03*
X724776D03*
G54D52*
X720782Y927445D03*
Y905559D03*
G54D16*
X106157Y985106D03*
Y983137D03*
Y981169D03*
Y979200D03*
Y977231D03*
Y975263D03*
Y973294D03*
Y971326D03*
Y969357D03*
Y989043D03*
Y987074D03*
X125443Y969357D03*
Y971326D03*
Y973294D03*
Y975263D03*
Y977231D03*
Y979200D03*
Y981169D03*
Y983137D03*
Y985106D03*
Y987074D03*
Y989043D03*
X172857Y577043D03*
Y575074D03*
Y573106D03*
Y571137D03*
Y569169D03*
Y567200D03*
Y565231D03*
Y563263D03*
Y561294D03*
Y559326D03*
Y557357D03*
X192143D03*
Y559326D03*
Y561294D03*
Y563263D03*
Y565231D03*
Y567200D03*
Y569169D03*
Y571137D03*
Y573106D03*
Y575074D03*
Y577043D03*
X1747957Y985294D03*
Y983326D03*
Y981357D03*
Y1001043D03*
Y999074D03*
Y997106D03*
Y995137D03*
Y993169D03*
Y991200D03*
Y989231D03*
Y987263D03*
X1767243Y981357D03*
Y983326D03*
Y985294D03*
Y987263D03*
Y989231D03*
Y991200D03*
Y993169D03*
Y995137D03*
Y997106D03*
Y999074D03*
Y1001043D03*
G54D25*
X114000Y995950D03*
X180700Y583950D03*
X1755800Y1007950D03*
G54D35*
X151256Y1002801D03*
X217956Y590801D03*
X745861Y868854D03*
X722625Y873544D03*
X1793056Y1014801D03*
X1847200Y907500D03*
G54D17*
X95363Y987725D03*
X87763D03*
X129700Y548400D03*
X137300D03*
X162063Y575725D03*
X154463D03*
X741782Y938102D03*
X749382D03*
X741782Y930302D03*
X749382D03*
X741782Y946002D03*
X749382D03*
X863032Y396400D03*
X870632D03*
X1057358Y394574D03*
X1064958D03*
X1735481Y1008554D03*
X1727881D03*
X1861617Y808535D03*
X1854017D03*
X1861617Y816335D03*
X1854017D03*
X1861617Y824135D03*
X1854017D03*
X1850800Y918500D03*
X1843200D03*
X1855800Y934500D03*
X1848200D03*
X1855200Y958500D03*
X1862800D03*
X1855800Y942500D03*
X1848200D03*
X1862700D03*
Y950500D03*
X1855800D03*
X1848200D03*
X1870300Y942500D03*
Y950500D03*
G54D53*
X763818Y888398D03*
Y877398D03*
G54D44*
X736938Y887518D03*
Y889486D03*
X724826D03*
Y887518D03*
G54D62*
X1860402Y925702D03*
X1858433D03*
Y906416D03*
X1860402D03*
X1878119Y925702D03*
X1876150D03*
X1874182D03*
X1872213D03*
X1870245D03*
X1868276D03*
X1866307D03*
X1864339D03*
X1862370D03*
Y906416D03*
X1864339D03*
X1866307D03*
X1868276D03*
X1870245D03*
X1872213D03*
X1874182D03*
X1876150D03*
X1878119D03*
G54D26*
X79563Y994472D03*
X140385Y572680D03*
X146263Y582472D03*
X126711Y959847D03*
X156063Y1007725D03*
X142563Y1006625D03*
X134063Y1003225D03*
X209163Y594425D03*
X200763Y591225D03*
X222763Y595725D03*
X631540Y589451D03*
X699883Y916689D03*
X700383Y940189D03*
X706084Y881450D03*
X746800Y872700D03*
X713883Y890189D03*
X727883Y877189D03*
X743000Y886200D03*
X737687Y872489D03*
X743200Y881658D03*
X731866Y873789D03*
X740883Y920189D03*
X740383Y911689D03*
X737683Y899989D03*
X746183Y901389D03*
X743883Y893289D03*
X768770Y868643D03*
X863900Y463100D03*
X848325Y480275D03*
X866100Y479900D03*
X856900Y479950D03*
X873000Y479900D03*
X864100Y492800D03*
X854600Y493000D03*
X891800Y1349965D03*
X888856Y1537644D03*
X941841Y1258580D03*
X903539Y1305368D03*
X920552Y1284112D03*
X966081Y1230097D03*
X1026100Y1363300D03*
X1023700Y1359525D03*
X1022232Y1414851D03*
X1035600Y1520600D03*
X1055881Y1006428D03*
X1065475Y1013261D03*
X1047700Y1481500D03*
X1548021Y544100D03*
X1554813Y548500D03*
X1713879Y1005156D03*
X1719681Y1015301D03*
X1799100Y1018400D03*
X1783963Y1018325D03*
X1775863Y1015225D03*
X1843200Y912813D03*
X1825821Y907899D03*
X1841065D03*
X1860570Y936809D03*
X1867763Y805386D03*
X1896801Y875796D03*
X1901442Y884012D03*
X1906010Y880553D03*
X1892673Y913996D03*
X1901442Y901000D03*
X1891098Y933500D03*
X1891616Y925702D03*
X1886814Y929000D03*
X1897507Y905750D03*
X1872024Y932518D03*
X1892473Y942674D03*
X1911676Y900821D03*
G54D63*
G01X363248Y-425196D02*
Y-505196D01*
G01D02*
X1639148D01*
G01X359248Y-409196D02*
G02I-12000J0D01*
G01X354098D02*
G02I-6850J0D01*
G01X347248Y-425196D02*
Y-393196D01*
G01X363248Y-425196D02*
X1639148D01*
G01X363248Y-460696D02*
X1639148D01*
G01X363248Y-409196D02*
X331248D01*
G01X720748Y-425196D02*
Y-505196D01*
G01X858248Y-425196D02*
Y-505196D01*
G01X973248Y-425196D02*
Y-505196D01*
G01X1271648Y-425196D02*
Y-505196D01*
G01X1441648Y-425196D02*
Y-505196D01*
G01X1639148Y-425196D02*
Y-505196D01*
G01X1667148Y-409196D02*
G02I-12000J0D01*
G01X1661998D02*
G02I-6850J0D01*
G01X1655148Y-425196D02*
Y-393196D01*
G01X1671148Y-409196D02*
X1639148D01*
G54D36*
X191400Y987400D03*
Y948300D03*
Y973100D03*
Y1012200D03*
X258100Y536300D03*
Y600200D03*
Y575400D03*
Y561100D03*
X1833200Y987700D03*
Y948600D03*
Y973400D03*
Y1012500D03*
G54D54*
X872366Y406550D03*
X861398D03*
X1066784Y404700D03*
X1055816D03*
G54D45*
X727929Y882396D03*
X733835D03*
Y894608D03*
X727929D03*
G54D27*
X172911Y968100D03*
X138289D03*
X204989Y556100D03*
X239611D03*
X1814711Y980100D03*
X1780089D03*
G54D18*
X96393Y981195D03*
X163093Y569195D03*
X751983Y920289D03*
X1736511Y1002024D03*
X1835866Y907899D03*
X1861800Y965000D03*
X1887520Y874918D03*
G54D64*
G01X394744Y-485863D02*
X395618Y-484988D01*
X396273Y-483530D01*
X396710Y-481487D01*
X396273Y-479738D01*
X395400Y-478571D01*
X393871Y-477696D01*
X387976D01*
Y-495196D01*
X395181D01*
X396710Y-494030D01*
X397583Y-492279D01*
X398020Y-490238D01*
X397583Y-488196D01*
X396273Y-486446D01*
X394744Y-485863D01*
X387976D01*
G01X407441Y-495196D02*
Y-483530D01*
G01Y-485863D02*
X408533Y-484696D01*
X409625Y-483821D01*
X411153Y-483530D01*
X412244Y-483821D01*
X413555Y-484696D01*
G01X423413Y-500446D02*
X424723Y-501029D01*
X426470Y-500446D01*
X427561Y-499280D01*
X428435Y-497821D01*
X429744Y-493155D01*
X432583Y-483530D01*
G01X425596D02*
X429744Y-493155D01*
G01X448991Y-484988D02*
X447463Y-483821D01*
X446153Y-483530D01*
X444406Y-484113D01*
X443096Y-485279D01*
X442223Y-487321D01*
X442004Y-489363D01*
X442223Y-491405D01*
X443096Y-493155D01*
X444406Y-494613D01*
X446153Y-495196D01*
X447681Y-494613D01*
X448991Y-493446D01*
G01X459723Y-487321D02*
X466710D01*
X466055Y-485279D01*
X464963Y-484113D01*
X463435Y-483530D01*
X461906Y-483821D01*
X460596Y-484696D01*
X459723Y-486738D01*
X459286Y-488488D01*
Y-490238D01*
X459723Y-491988D01*
X460815Y-493738D01*
X462125Y-494904D01*
X463653Y-495196D01*
X465181Y-494613D01*
X466710Y-492863D01*
G01X502801Y-479155D02*
X501491Y-478279D01*
X499963Y-477696D01*
X498216D01*
X496251Y-478571D01*
X494723Y-480029D01*
X493631Y-481780D01*
X492758Y-484696D01*
X492539Y-487321D01*
X492976Y-489946D01*
X493631Y-491696D01*
X494941Y-493446D01*
X496470Y-494613D01*
X497998Y-495196D01*
X499526D01*
X501055Y-494613D01*
X502365Y-493738D01*
X503457Y-492572D01*
G01X519428Y-495196D02*
Y-483530D01*
G01Y-485571D02*
X518555Y-484405D01*
X517244Y-483821D01*
X515716Y-483530D01*
X514188Y-484113D01*
X512878Y-485279D01*
X512004Y-487029D01*
X511568Y-489363D01*
X512004Y-491696D01*
X512878Y-493446D01*
X514188Y-494613D01*
X515716Y-495196D01*
X517244Y-494904D01*
X518555Y-494030D01*
X519428Y-492863D01*
G01X529286Y-495196D02*
Y-483530D01*
G01Y-486446D02*
X530160Y-484988D01*
X531470Y-483821D01*
X533216Y-483530D01*
X534744Y-483821D01*
X536055Y-484988D01*
X536710Y-487029D01*
Y-495196D01*
G01X545913Y-500446D02*
X547223Y-501029D01*
X548970Y-500446D01*
X550061Y-499280D01*
X550935Y-497821D01*
X552244Y-493155D01*
X555083Y-483530D01*
G01X548096D02*
X552244Y-493155D01*
G01X567998Y-495196D02*
X566688Y-494904D01*
X565378Y-493738D01*
X564504Y-491696D01*
X564068Y-489363D01*
X564504Y-487029D01*
X565378Y-484988D01*
X566688Y-483821D01*
X567998Y-483530D01*
X569308Y-483821D01*
X570618Y-484988D01*
X571491Y-487029D01*
X571710Y-489363D01*
X571491Y-491696D01*
X570618Y-493738D01*
X569308Y-494904D01*
X567998Y-495196D01*
G01X581786D02*
Y-483530D01*
G01Y-486446D02*
X582660Y-484988D01*
X583970Y-483821D01*
X585716Y-483530D01*
X587244Y-483821D01*
X588555Y-484988D01*
X589210Y-487029D01*
Y-495196D01*
G01X616350D02*
Y-477696D01*
X624646D01*
G01X621590Y-486154D02*
X616350D01*
G01X637998Y-495779D02*
X637561Y-495488D01*
Y-494904D01*
X637998Y-494613D01*
X638435Y-494904D01*
Y-495488D01*
X637998Y-495779D01*
G01X650695Y-495196D02*
Y-477696D01*
X655061D01*
X656808Y-478571D01*
X658118Y-479738D01*
X659210Y-481487D01*
X660083Y-483530D01*
X660301Y-486446D01*
X660083Y-489363D01*
X659210Y-491405D01*
X658118Y-493155D01*
X656808Y-494321D01*
X655061Y-495196D01*
X650695D01*
G01X668631D02*
Y-477696D01*
X673871D01*
X675618Y-478571D01*
X676928Y-480613D01*
X677365Y-482946D01*
X676928Y-485279D01*
X675836Y-487029D01*
X673871Y-487905D01*
X668631D01*
G01X692244Y-485863D02*
X693118Y-484988D01*
X693773Y-483530D01*
X694210Y-481487D01*
X693773Y-479738D01*
X692900Y-478571D01*
X691371Y-477696D01*
X685476D01*
Y-495196D01*
X692681D01*
X694210Y-494030D01*
X695083Y-492279D01*
X695520Y-490238D01*
X695083Y-488196D01*
X693773Y-486446D01*
X692244Y-485863D01*
X685476D01*
G01X501071Y-450196D02*
Y-432696D01*
X506748Y-447279D01*
X512425Y-432696D01*
Y-450196D01*
G01X524248D02*
X522938Y-449904D01*
X521628Y-448738D01*
X520754Y-446696D01*
X520318Y-444363D01*
X520754Y-442029D01*
X521628Y-439988D01*
X522938Y-438821D01*
X524248Y-438530D01*
X525558Y-438821D01*
X526868Y-439988D01*
X527741Y-442029D01*
X527960Y-444363D01*
X527741Y-446696D01*
X526868Y-448738D01*
X525558Y-449904D01*
X524248Y-450196D01*
G01X545678Y-432696D02*
Y-450196D01*
G01Y-447572D02*
X544805Y-449030D01*
X543494Y-449904D01*
X541966Y-450196D01*
X540220Y-449613D01*
X538910Y-448155D01*
X538036Y-446405D01*
X537818Y-444363D01*
X538036Y-442321D01*
X538910Y-440571D01*
X540220Y-439113D01*
X541966Y-438530D01*
X543494Y-438821D01*
X544586Y-439405D01*
X545678Y-440571D01*
G01X555973Y-442321D02*
X562960D01*
X562305Y-440279D01*
X561213Y-439113D01*
X559685Y-438530D01*
X558156Y-438821D01*
X556846Y-439696D01*
X555973Y-441738D01*
X555536Y-443488D01*
Y-445238D01*
X555973Y-446988D01*
X557065Y-448738D01*
X558375Y-449904D01*
X559903Y-450196D01*
X561431Y-449613D01*
X562960Y-447863D01*
G01X576748Y-450196D02*
Y-432696D01*
G01X754448Y-495196D02*
Y-477696D01*
X751828Y-481196D01*
G01Y-495196D02*
X757068D01*
G01X767800Y-487905D02*
X769328Y-485863D01*
X770638Y-484696D01*
X772385Y-484113D01*
X773913Y-484696D01*
X775005Y-485863D01*
X775878Y-487613D01*
X776096Y-489654D01*
X775878Y-491405D01*
X775005Y-493155D01*
X773694Y-494613D01*
X772166Y-495196D01*
X770420Y-494613D01*
X768891Y-492863D01*
X768018Y-490238D01*
X767800Y-487321D01*
X768236Y-483530D01*
X768891Y-481487D01*
X769983Y-479446D01*
X771511Y-477988D01*
X773040Y-477696D01*
X774568Y-478279D01*
X775660Y-479738D01*
G01X784645Y-491696D02*
X785954Y-493738D01*
X787701Y-494904D01*
X789666Y-495196D01*
X791413Y-494904D01*
X793160Y-493446D01*
X794251Y-491696D01*
X794470Y-489946D01*
X794033Y-487905D01*
X792505Y-486446D01*
X790976Y-485863D01*
X789011D01*
G01X790976D02*
X792286Y-484988D01*
X793378Y-483530D01*
X793815Y-481780D01*
X793378Y-480029D01*
X792286Y-478571D01*
X790321Y-477696D01*
X788356Y-477988D01*
X786391Y-479155D01*
G01X806948Y-495196D02*
Y-477696D01*
X804328Y-481196D01*
G01Y-495196D02*
X809568D01*
G01X819645Y-492572D02*
X820954Y-494030D01*
X822483Y-494904D01*
X824448Y-495196D01*
X826413Y-494613D01*
X827941Y-493446D01*
X829033Y-491405D01*
X829251Y-489071D01*
X828815Y-486738D01*
X827723Y-485279D01*
X826194Y-484113D01*
X824666Y-483821D01*
X823138Y-484113D01*
X821173Y-485279D01*
X821828Y-477696D01*
X827723D01*
G01X741331Y-450196D02*
Y-432696D01*
X746571D01*
X748318Y-433571D01*
X749628Y-435613D01*
X750065Y-437946D01*
X749628Y-440279D01*
X748536Y-442029D01*
X746571Y-442905D01*
X741331D01*
G01X768001Y-434155D02*
X766691Y-433279D01*
X765163Y-432696D01*
X763416D01*
X761451Y-433571D01*
X759923Y-435029D01*
X758831Y-436780D01*
X757958Y-439696D01*
X757739Y-442321D01*
X758176Y-444946D01*
X758831Y-446696D01*
X760141Y-448446D01*
X761670Y-449613D01*
X763198Y-450196D01*
X764726D01*
X766255Y-449613D01*
X767565Y-448738D01*
X768657Y-447572D01*
G01X782444Y-440863D02*
X783318Y-439988D01*
X783973Y-438530D01*
X784410Y-436487D01*
X783973Y-434738D01*
X783100Y-433571D01*
X781571Y-432696D01*
X775676D01*
Y-450196D01*
X782881D01*
X784410Y-449030D01*
X785283Y-447279D01*
X785720Y-445238D01*
X785283Y-443196D01*
X783973Y-441446D01*
X782444Y-440863D01*
X775676D01*
G01X791648Y-456029D02*
X804748D01*
G01X810676Y-450196D02*
Y-432696D01*
X820720Y-450196D01*
Y-432696D01*
G01X833198Y-450196D02*
X831451Y-449904D01*
X829923Y-448738D01*
X828613Y-446988D01*
X827739Y-444946D01*
X827303Y-442613D01*
Y-440279D01*
X827739Y-437946D01*
X828613Y-435904D01*
X829923Y-434155D01*
X831451Y-432988D01*
X833198Y-432696D01*
X834944Y-432988D01*
X836473Y-434155D01*
X837783Y-435904D01*
X838657Y-437946D01*
X839093Y-440279D01*
Y-442613D01*
X838657Y-444946D01*
X837783Y-446988D01*
X836473Y-448738D01*
X834944Y-449904D01*
X833198Y-450196D01*
G01X884039Y-432696D02*
X889498Y-450196D01*
X894957Y-432696D01*
G01X911365Y-450196D02*
X902631D01*
Y-432696D01*
X911365D01*
G01X907871Y-441154D02*
X902631D01*
G01X920131Y-450196D02*
Y-432696D01*
X925590D01*
X927336Y-433571D01*
X928428Y-434738D01*
X928865Y-437071D01*
X928428Y-439405D01*
X927118Y-440863D01*
X925590Y-441738D01*
X920131D01*
G01X925590D02*
X928865Y-450196D01*
G01X941998Y-450779D02*
X941561Y-450488D01*
Y-449904D01*
X941998Y-449613D01*
X942435Y-449904D01*
Y-450488D01*
X941998Y-450779D01*
G01X915748Y-495196D02*
Y-477696D01*
X913128Y-481196D01*
G01Y-495196D02*
X918368D01*
G01X1082981Y-432696D02*
Y-450196D01*
X1091715D01*
G01X1108778D02*
Y-438530D01*
G01Y-440571D02*
X1107905Y-439405D01*
X1106594Y-438821D01*
X1105066Y-438530D01*
X1103538Y-439113D01*
X1102228Y-440279D01*
X1101354Y-442029D01*
X1100918Y-444363D01*
X1101354Y-446696D01*
X1102228Y-448446D01*
X1103538Y-449613D01*
X1105066Y-450196D01*
X1106594Y-449904D01*
X1107905Y-449030D01*
X1108778Y-447863D01*
G01X1117763Y-455446D02*
X1119073Y-456029D01*
X1120820Y-455446D01*
X1121911Y-454280D01*
X1122785Y-452821D01*
X1124094Y-448155D01*
X1126933Y-438530D01*
G01X1119946D02*
X1124094Y-448155D01*
G01X1136573Y-442321D02*
X1143560D01*
X1142905Y-440279D01*
X1141813Y-439113D01*
X1140285Y-438530D01*
X1138756Y-438821D01*
X1137446Y-439696D01*
X1136573Y-441738D01*
X1136136Y-443488D01*
Y-445238D01*
X1136573Y-446988D01*
X1137665Y-448738D01*
X1138975Y-449904D01*
X1140503Y-450196D01*
X1142031Y-449613D01*
X1143560Y-447863D01*
G01X1154291Y-450196D02*
Y-438530D01*
G01Y-440863D02*
X1155383Y-439696D01*
X1156475Y-438821D01*
X1158003Y-438530D01*
X1159094Y-438821D01*
X1160405Y-439696D01*
G01X1146852Y-485863D02*
X1145978Y-484988D01*
X1145323Y-483530D01*
X1144886Y-481487D01*
X1145323Y-479738D01*
X1146196Y-478571D01*
X1147725Y-477696D01*
X1153620D01*
Y-495196D01*
X1146415D01*
X1144886Y-494030D01*
X1144013Y-492279D01*
X1143576Y-490238D01*
X1144013Y-488196D01*
X1145323Y-486446D01*
X1146852Y-485863D01*
X1153620D01*
G01X1135683Y-492863D02*
X1133936Y-494321D01*
X1131971Y-495196D01*
X1130225D01*
X1128478Y-494321D01*
X1127168Y-492863D01*
X1126513Y-490821D01*
X1126950Y-488780D01*
X1128041Y-487029D01*
X1130006Y-485863D01*
X1132626Y-485279D01*
X1134155Y-484113D01*
X1134810Y-482071D01*
X1134373Y-480029D01*
X1133281Y-478571D01*
X1131753Y-477696D01*
X1130225D01*
X1128696Y-478279D01*
X1127386Y-479738D01*
G01X1119275Y-495196D02*
Y-477696D01*
X1113598Y-492279D01*
X1107921Y-477696D01*
Y-495196D01*
G01X1100901D02*
Y-477696D01*
X1096535D01*
X1094788Y-478571D01*
X1093478Y-479738D01*
X1092386Y-481487D01*
X1091513Y-483530D01*
X1091295Y-486446D01*
X1091513Y-489363D01*
X1092386Y-491405D01*
X1093478Y-493155D01*
X1094788Y-494321D01*
X1096535Y-495196D01*
X1100901D01*
G01X1312898D02*
X1311151Y-494904D01*
X1309623Y-493738D01*
X1308313Y-491988D01*
X1307439Y-489946D01*
X1307003Y-487613D01*
Y-485279D01*
X1307439Y-482946D01*
X1308313Y-480904D01*
X1309623Y-479155D01*
X1311151Y-477988D01*
X1312898Y-477696D01*
X1314644Y-477988D01*
X1316173Y-479155D01*
X1317483Y-480904D01*
X1318357Y-482946D01*
X1318793Y-485279D01*
Y-487613D01*
X1318357Y-489946D01*
X1317483Y-491988D01*
X1316173Y-493738D01*
X1314644Y-494904D01*
X1312898Y-495196D01*
G01X1314644Y-490529D02*
X1317265Y-495196D01*
G01X1325595Y-477696D02*
Y-490238D01*
X1326468Y-492863D01*
X1328215Y-494613D01*
X1330398Y-495196D01*
X1332581Y-494613D01*
X1334328Y-492863D01*
X1335201Y-490238D01*
Y-477696D01*
G01X1345278D02*
X1350518D01*
G01X1347898D02*
Y-495196D01*
G01X1345278D02*
X1350518D01*
G01X1360376D02*
Y-477696D01*
X1370420Y-495196D01*
Y-477696D01*
G01X1387701Y-479155D02*
X1386391Y-478279D01*
X1384863Y-477696D01*
X1383116D01*
X1381151Y-478571D01*
X1379623Y-480029D01*
X1378531Y-481780D01*
X1377658Y-484696D01*
X1377439Y-487321D01*
X1377876Y-489946D01*
X1378531Y-491696D01*
X1379841Y-493446D01*
X1381370Y-494613D01*
X1382898Y-495196D01*
X1384426D01*
X1385955Y-494613D01*
X1387265Y-493738D01*
X1388357Y-492572D01*
G01X1400398Y-495196D02*
Y-487321D01*
X1396031Y-477696D01*
G01X1404765D02*
X1400398Y-487321D01*
G01X1290595Y-450196D02*
Y-432696D01*
X1294961D01*
X1296708Y-433571D01*
X1298018Y-434738D01*
X1299110Y-436487D01*
X1299983Y-438530D01*
X1300201Y-441446D01*
X1299983Y-444363D01*
X1299110Y-446405D01*
X1298018Y-448155D01*
X1296708Y-449321D01*
X1294961Y-450196D01*
X1290595D01*
G01X1309623Y-442321D02*
X1316610D01*
X1315955Y-440279D01*
X1314863Y-439113D01*
X1313335Y-438530D01*
X1311806Y-438821D01*
X1310496Y-439696D01*
X1309623Y-441738D01*
X1309186Y-443488D01*
Y-445238D01*
X1309623Y-446988D01*
X1310715Y-448738D01*
X1312025Y-449904D01*
X1313553Y-450196D01*
X1315081Y-449613D01*
X1316610Y-447863D01*
G01X1327123Y-448155D02*
X1328215Y-449321D01*
X1329743Y-450196D01*
X1331053D01*
X1332363Y-449613D01*
X1333236Y-448738D01*
X1333673Y-447572D01*
X1333455Y-445821D01*
X1332581Y-444946D01*
X1328651Y-443196D01*
X1327778Y-441154D01*
X1328215Y-439696D01*
X1329088Y-438821D01*
X1330398Y-438530D01*
X1331708Y-438821D01*
X1333018Y-439696D01*
G01X1347898Y-438530D02*
Y-450196D01*
G01Y-433863D02*
X1347461Y-433571D01*
Y-432988D01*
X1347898Y-432696D01*
X1348335Y-432988D01*
Y-433571D01*
X1347898Y-433863D01*
G01X1362341Y-454571D02*
X1363870Y-455738D01*
X1365616Y-456029D01*
X1367144Y-455738D01*
X1368455Y-454280D01*
X1369328Y-452238D01*
Y-438530D01*
G01Y-440863D02*
X1368455Y-439696D01*
X1367144Y-438821D01*
X1365616Y-438530D01*
X1363870Y-439113D01*
X1362778Y-440279D01*
X1361904Y-442321D01*
X1361468Y-444363D01*
X1361686Y-446113D01*
X1362560Y-448155D01*
X1363870Y-449613D01*
X1365616Y-450196D01*
X1366926Y-449904D01*
X1368455Y-448738D01*
X1369328Y-447572D01*
G01X1379186Y-450196D02*
Y-438530D01*
G01Y-441446D02*
X1380060Y-439988D01*
X1381370Y-438821D01*
X1383116Y-438530D01*
X1384644Y-438821D01*
X1385955Y-439988D01*
X1386610Y-442029D01*
Y-450196D01*
G01X1397123Y-442321D02*
X1404110D01*
X1403455Y-440279D01*
X1402363Y-439113D01*
X1400835Y-438530D01*
X1399306Y-438821D01*
X1397996Y-439696D01*
X1397123Y-441738D01*
X1396686Y-443488D01*
Y-445238D01*
X1397123Y-446988D01*
X1398215Y-448738D01*
X1399525Y-449904D01*
X1401053Y-450196D01*
X1402581Y-449613D01*
X1404110Y-447863D01*
G01X1414841Y-450196D02*
Y-438530D01*
G01Y-440863D02*
X1415933Y-439696D01*
X1417025Y-438821D01*
X1418553Y-438530D01*
X1419644Y-438821D01*
X1420955Y-439696D01*
G01X1461598Y-477696D02*
X1459851Y-478279D01*
X1458541Y-479738D01*
X1457668Y-481487D01*
X1457013Y-483821D01*
X1456795Y-486446D01*
X1457013Y-489071D01*
X1457668Y-491405D01*
X1458541Y-493155D01*
X1459851Y-494613D01*
X1461598Y-495196D01*
X1463344Y-494613D01*
X1464655Y-493155D01*
X1465528Y-491405D01*
X1466183Y-489071D01*
X1466401Y-486446D01*
X1466183Y-483821D01*
X1465528Y-481487D01*
X1464655Y-479738D01*
X1463344Y-478279D01*
X1461598Y-477696D01*
G01X1474950Y-487905D02*
X1476478Y-485863D01*
X1477788Y-484696D01*
X1479535Y-484113D01*
X1481063Y-484696D01*
X1482155Y-485863D01*
X1483028Y-487613D01*
X1483246Y-489654D01*
X1483028Y-491405D01*
X1482155Y-493155D01*
X1480844Y-494613D01*
X1479316Y-495196D01*
X1477570Y-494613D01*
X1476041Y-492863D01*
X1475168Y-490238D01*
X1474950Y-487321D01*
X1475386Y-483530D01*
X1476041Y-481487D01*
X1477133Y-479446D01*
X1478661Y-477988D01*
X1480190Y-477696D01*
X1481718Y-478279D01*
X1482810Y-479738D01*
G01X1492668Y-495779D02*
X1500528Y-477696D01*
G01X1514098D02*
X1512351Y-478279D01*
X1511041Y-479738D01*
X1510168Y-481487D01*
X1509513Y-483821D01*
X1509295Y-486446D01*
X1509513Y-489071D01*
X1510168Y-491405D01*
X1511041Y-493155D01*
X1512351Y-494613D01*
X1514098Y-495196D01*
X1515844Y-494613D01*
X1517155Y-493155D01*
X1518028Y-491405D01*
X1518683Y-489071D01*
X1518901Y-486446D01*
X1518683Y-483821D01*
X1518028Y-481487D01*
X1517155Y-479738D01*
X1515844Y-478279D01*
X1514098Y-477696D01*
G01X1527886Y-493155D02*
X1529415Y-494613D01*
X1531161Y-495196D01*
X1532908Y-494613D01*
X1534436Y-492863D01*
X1535528Y-490238D01*
X1535965Y-487613D01*
Y-484405D01*
X1535528Y-481780D01*
X1534436Y-479446D01*
X1533126Y-478279D01*
X1531598Y-477696D01*
X1529851Y-478279D01*
X1528541Y-479446D01*
X1527668Y-481196D01*
X1527231Y-483530D01*
X1527668Y-485571D01*
X1528760Y-487613D01*
X1530070Y-488780D01*
X1531598Y-489071D01*
X1533344Y-488488D01*
X1534655Y-487029D01*
X1535965Y-484405D01*
G01X1545168Y-495779D02*
X1553028Y-477696D01*
G01X1562450Y-480613D02*
X1563760Y-478863D01*
X1565288Y-477988D01*
X1567035Y-477696D01*
X1569218Y-478279D01*
X1570746Y-479738D01*
X1571183Y-481487D01*
X1570965Y-483238D01*
X1570091Y-484696D01*
X1565725Y-487613D01*
X1563760Y-489654D01*
X1562450Y-492572D01*
X1562013Y-495196D01*
X1571183D01*
G01X1584098Y-477696D02*
X1582351Y-478279D01*
X1581041Y-479738D01*
X1580168Y-481487D01*
X1579513Y-483821D01*
X1579295Y-486446D01*
X1579513Y-489071D01*
X1580168Y-491405D01*
X1581041Y-493155D01*
X1582351Y-494613D01*
X1584098Y-495196D01*
X1585844Y-494613D01*
X1587155Y-493155D01*
X1588028Y-491405D01*
X1588683Y-489071D01*
X1588901Y-486446D01*
X1588683Y-483821D01*
X1588028Y-481487D01*
X1587155Y-479738D01*
X1585844Y-478279D01*
X1584098Y-477696D01*
G01X1601598Y-495196D02*
Y-477696D01*
X1598978Y-481196D01*
G01Y-495196D02*
X1604218D01*
G01X1618661D02*
X1619098Y-491405D01*
X1619753Y-488196D01*
X1620626Y-485279D01*
X1621718Y-482071D01*
X1623465Y-477696D01*
X1614731D01*
G01X1509295Y-450196D02*
Y-432696D01*
X1513661D01*
X1515408Y-433571D01*
X1516718Y-434738D01*
X1517810Y-436487D01*
X1518683Y-438530D01*
X1518901Y-441446D01*
X1518683Y-444363D01*
X1517810Y-446405D01*
X1516718Y-448155D01*
X1515408Y-449321D01*
X1513661Y-450196D01*
X1509295D01*
G01X1535528D02*
Y-438530D01*
G01Y-440571D02*
X1534655Y-439405D01*
X1533344Y-438821D01*
X1531816Y-438530D01*
X1530288Y-439113D01*
X1528978Y-440279D01*
X1528104Y-442029D01*
X1527668Y-444363D01*
X1528104Y-446696D01*
X1528978Y-448446D01*
X1530288Y-449613D01*
X1531816Y-450196D01*
X1533344Y-449904D01*
X1534655Y-449030D01*
X1535528Y-447863D01*
G01X1549098Y-432696D02*
Y-450196D01*
G01X1546041Y-438530D02*
X1552155D01*
G01X1563323Y-442321D02*
X1570310D01*
X1569655Y-440279D01*
X1568563Y-439113D01*
X1567035Y-438530D01*
X1565506Y-438821D01*
X1564196Y-439696D01*
X1563323Y-441738D01*
X1562886Y-443488D01*
Y-445238D01*
X1563323Y-446988D01*
X1564415Y-448738D01*
X1565725Y-449904D01*
X1567253Y-450196D01*
X1568781Y-449613D01*
X1570310Y-447863D01*
G01X0Y-137756D02*
G03X15000Y-152756I15000J0D01*
G01X0Y-137756D02*
G03X15000Y-152756I15000J0D01*
G01X0Y-11811D02*
Y-137756D01*
G01Y-11811D02*
Y-137756D01*
G01X854331Y-152756D02*
X15000D01*
G01X854331D02*
X15000D01*
G01X23622Y-7874D02*
G03Y0I0J3937D01*
G01Y-7874D02*
G03Y0I0J3937D01*
G01X0Y3937D02*
G03X3937Y0I3937J0D01*
G01Y-7874D02*
X23622D01*
G01X0Y3937D02*
G03X3937Y0I3937J0D01*
G01Y-7874D02*
X23622D01*
G01X3937D02*
G03X0Y-11811I0J-3937D01*
G01X3937Y-7874D02*
G03X0Y-11811I0J-3937D01*
G01X3937Y0D02*
X397638D01*
G01X3937D02*
X397638D01*
G01X0Y1370866D02*
Y3937D01*
G01Y1370866D02*
Y3937D01*
G01X3937Y1374803D02*
G03X0Y1370866I0J-3937D01*
G01X3937Y1374803D02*
G03X0Y1370866I0J-3937D01*
G01X23622Y1374803D02*
G03Y1382677I0J3937D01*
G01Y1374803D02*
G03Y1382677I0J3937D01*
G01X3937D02*
X23622D01*
G01X0Y1386614D02*
G03X3937Y1382677I3937J0D01*
G01D02*
X23622D01*
G01X0Y1386614D02*
G03X3937Y1382677I3937J0D01*
G01Y1374803D02*
X746850D01*
G01D02*
X3937D01*
G01X0Y1386614D02*
Y1643268D01*
G01Y1386614D02*
Y1643268D01*
G01X15000Y1658268D02*
G03X0Y1643268I0J-15000D01*
G01X15000Y1658268D02*
G03X0Y1643268I0J-15000D01*
G01X775591Y1658268D02*
X15000D01*
G01X775591D02*
X15000D01*
G01X54331Y-7874D02*
X323228D01*
G01X54331D02*
X323228D01*
G01X54331Y0D02*
G03Y-7874I0J-3937D01*
G01Y0D02*
G03Y-7874I0J-3937D01*
G01Y1382677D02*
G03Y1374803I0J-3937D01*
G01Y1382677D02*
G03Y1374803I0J-3937D01*
G01Y1382677D02*
X353740D01*
G01X54331D02*
X353740D01*
G01X114295Y378885D02*
G03X148106I16905J-13531D01*
G01X114295D02*
G03X148106I16905J-13531D01*
G01X114295D02*
G03X121220Y392016I-30737J24602D01*
G01X114295Y378885D02*
G03X121220Y392016I-30737J24602D01*
G01X114295Y831641D02*
G03X121220Y844772I-30737J24601D01*
G01X114295Y831641D02*
G03X121220Y844772I-30737J24602D01*
G01X114295Y831641D02*
G03X148106I16905J-13531D01*
G01X114295D02*
G03X148106I16905J-13531D01*
G01X114295Y1284397D02*
G03X148106I16905J-13531D01*
G01X114295D02*
G03X148106I16905J-13531D01*
G01X114295D02*
G03X121220Y1297528I-30737J24601D01*
G01X114295Y1284397D02*
G03X121220Y1297528I-30737J24602D01*
G01X141181Y392016D02*
G03X121220I-9980J-3039D01*
G01X141181D02*
G03X148106Y378885I37662J11471D01*
G01X141181Y392016D02*
G03X121220I-9980J-3039D01*
G01X141181D02*
G03X148106Y378885I37662J11471D01*
G01X141181Y844772D02*
G03X148106Y831641I37662J11471D01*
G01X141181Y844772D02*
G03X148106Y831641I37662J11471D01*
G01X141181Y844772D02*
G03X121220I-9980J-3040D01*
G01X141181D02*
G03X121220I-9980J-3039D01*
G01X141181Y1297528D02*
G03X121220I-9980J-3040D01*
G01X141181D02*
G03X148106Y1284397I37662J11471D01*
G01X141181Y1297528D02*
G03X121220I-9980J-3040D01*
G01X141181D02*
G03X148106Y1284397I37662J11471D01*
G01X323228Y-7874D02*
G03Y0I0J3937D01*
G01Y-7874D02*
G03Y0I0J3937D01*
G01X362598D02*
G03Y-7874I0J-3937D01*
G01Y0D02*
G03Y-7874I0J-3937D01*
G01X362327Y378885D02*
G03X396138I16905J-13531D01*
G01X362327D02*
G03X396138I16905J-13531D01*
G01X362327D02*
G03X369252Y392016I-30737J24602D01*
G01X362327Y378885D02*
G03X369252Y392016I-30737J24602D01*
G01X362327Y831641D02*
G03X369252Y844772I-30737J24602D01*
G01X362327Y831641D02*
G03X369252Y844772I-30737J24602D01*
G01X362327Y831641D02*
G03X396138I16905J-13531D01*
G01X362327D02*
G03X396138I16905J-13531D01*
G01X362327Y1284397D02*
G03X396138I16905J-13531D01*
G01X362327D02*
G03X396138I16905J-13531D01*
G01X362327D02*
G03X369252Y1297528I-30737J24602D01*
G01X362327Y1284397D02*
G03X369252Y1297528I-30737J24602D01*
G01X353740Y1374803D02*
G03Y1382677I0J3937D01*
G01Y1374803D02*
G03Y1382677I0J3937D01*
G01X401575Y3937D02*
Y55118D01*
G01X397638Y0D02*
G03X401575Y3937I0J3937D01*
G01X409449D02*
Y51181D01*
G01X397638Y-7874D02*
G03X409449Y3937I0J11811D01*
G01X397638Y0D02*
G03X401575Y3937I0J3937D01*
G01D02*
Y55118D01*
G01X409449Y3937D02*
Y51181D01*
G01X397638Y-7874D02*
G03X409449Y3937I0J11811D01*
G01X362598Y-7874D02*
X397638D01*
G01X362598D02*
X397638D01*
G01X405512Y59055D02*
G03X401575Y55118I0J-3937D01*
G01X405512Y59055D02*
G03X401575Y55118I0J-3937D01*
G01X405512Y59055D02*
X586614D01*
G01X409449Y51181D02*
X582677D01*
G01X405512Y59055D02*
X586614D01*
G01X409449Y51181D02*
X582677D01*
G01X389213Y392016D02*
G03X396138Y378885I37662J11471D01*
G01X389213Y392016D02*
G03X396138Y378885I37662J11471D01*
G01X389213Y392016D02*
G03X369252I-9981J-3039D01*
G01X389213D02*
G03X369252I-9981J-3039D01*
G01X389213Y844772D02*
G03X396138Y831641I37662J11471D01*
G01X389213Y844772D02*
G03X396138Y831641I37662J11471D01*
G01X389213Y844772D02*
G03X369252I-9981J-3040D01*
G01X389213D02*
G03X369252I-9981J-3039D01*
G01X389213Y1297528D02*
G03X396138Y1284397I37662J11471D01*
G01X389213Y1297528D02*
G03X396138Y1284397I37662J11471D01*
G01X389213Y1297528D02*
G03X369252I-9981J-3040D01*
G01X389213D02*
G03X369252I-9981J-3040D01*
G01X393110Y1382677D02*
G03Y1374803I0J-3937D01*
G01Y1382677D02*
X692520D01*
G01X393110D02*
X692520D01*
G01X393110D02*
G03Y1374803I0J-3937D01*
G01X523327Y829921D02*
G03X483169I-20079J0D01*
G01X523327D02*
G03I-20079J0D01*
G01X483169D02*
G03X523327I20079J0D01*
G01X594488Y-7874D02*
X628765D01*
G01X594488D02*
X628765D01*
G01X590551Y55118D02*
Y3937D01*
G01D02*
G03X594488Y0I3937J0D01*
G01X582677Y51181D02*
Y3937D01*
G01D02*
G03X594488Y-7874I11811J0D01*
G01X590551Y55118D02*
Y3937D01*
G01D02*
G03X594488Y0I3937J0D01*
G01X582677Y51181D02*
Y3937D01*
G01D02*
G03X594488Y-7874I11811J0D01*
G01Y0D02*
X783465D01*
G01X594488D02*
X783465D01*
G01X590551Y55118D02*
G03X586614Y59055I-3937J0D01*
G01X590551Y55118D02*
G03X586614Y59055I-3937J0D01*
G01X628765Y-7874D02*
G03Y0I0J3937D01*
G01Y-7874D02*
G03Y0I0J3937D01*
G01X610358Y378885D02*
G03X644169I16906J-13531D01*
G01X610358D02*
G03X644169I16906J-13531D01*
G01X637244Y392016D02*
G03X644169Y378885I37662J11471D01*
G01X637244Y392016D02*
G03X644169Y378885I37662J11471D01*
G01X637244Y392016D02*
G03X617283I-9980J-3039D01*
G01X637244D02*
G03X617283I-9980J-3039D01*
G01X610358Y378885D02*
G03X617283Y392016I-30737J24602D01*
G01X610358Y378885D02*
G03X617283Y392016I-30737J24602D01*
G01X637244Y844772D02*
G03X644169Y831641I37662J11471D01*
G01X637244Y844772D02*
G03X644169Y831641I37662J11471D01*
G01X610358D02*
G03X617283Y844772I-30737J24601D01*
G01X610358Y831641D02*
G03X617283Y844772I-30737J24602D01*
G01X610358Y831641D02*
G03X644169I16906J-13531D01*
G01X610358D02*
G03X644169I16906J-13531D01*
G01X637244Y844772D02*
G03X617283I-9980J-3040D01*
G01X637244D02*
G03X617283I-9980J-3039D01*
G01X610358Y1284397D02*
G03X644169I16906J-13531D01*
G01X610358D02*
G03X644169I16906J-13531D01*
G01X637244Y1297528D02*
G03X644169Y1284397I37662J11471D01*
G01X637244Y1297528D02*
G03X644169Y1284397I37662J11471D01*
G01X610358D02*
G03X617283Y1297528I-30737J24601D01*
G01X637244D02*
G03X617283I-9980J-3040D01*
G01X610358Y1284397D02*
G03X617283Y1297528I-30737J24602D01*
G01X637244D02*
G03X617283I-9980J-3040D01*
G01X659474Y0D02*
G03Y-7874I0J-3937D01*
G01Y0D02*
G03Y-7874I0J-3937D01*
G01D02*
X780203D01*
G01X659474D02*
X780203D01*
G01X692520Y1374803D02*
G03Y1382677I0J3937D01*
G01Y1374803D02*
G03Y1382677I0J3937D01*
G01X746850Y1374803D02*
G03X750787Y1378740I0J3937D01*
G01X746850Y1374803D02*
G03X750787Y1378740I0J3937D01*
G01X723228Y1382677D02*
G03Y1374803I0J-3937D01*
G01Y1382677D02*
X742913D01*
G01X723228D02*
X742913D01*
G01X723228D02*
G03Y1374803I0J-3937D01*
G01X742913Y1464567D02*
Y1382677D01*
G01Y1464567D02*
Y1382677D01*
G01X754724Y1476378D02*
G03X742913Y1464567I0J-11811D01*
G01X754724Y1476378D02*
G03X742913Y1464567I0J-11811D01*
G01X862205Y-7874D02*
X791339D01*
G01X787402Y-3937D02*
G03X791339Y-7874I3937J0D01*
G01X787402Y-3937D02*
G03X791339Y-7874I3937J0D01*
G01D02*
X862205D01*
G01X858268Y-15748D02*
X791339D01*
G01X858268D02*
X791339D01*
G01X787402Y-3937D02*
G03X783465Y0I-3937J0D01*
G01X787402Y-3937D02*
G03X783465Y0I-3937J0D01*
G01X780203Y-7874D02*
G03X791339Y-15748I11136J3937D01*
G01X780203Y-7874D02*
G03X791339Y-15748I11136J3937D01*
G01X779551Y264712D02*
G03X813362I16905J-13531D01*
G01X779551D02*
G03X813362I16905J-13531D01*
G01X779551D02*
G03X786476Y277843I-30737J24601D01*
G01X806437D02*
G03X786476I-9981J-3040D01*
G01X779551Y264712D02*
G03X786476Y277843I-30737J24602D01*
G01X806437D02*
G03X786476I-9981J-3040D01*
G01X779551Y737153D02*
G03X786476Y750284I-30737J24601D01*
G01X779551Y737154D02*
G03X786476Y750284I-30736J24602D01*
G01X779551Y737153D02*
G03X813362I16905J-13531D01*
G01X779551D02*
G03X813362I16905J-13531D01*
G01X806437Y750284D02*
G03X786476I-9981J-3040D01*
G01X806437D02*
G03X786476I-9981J-3040D01*
G01X750787Y1464567D02*
Y1378740D01*
G01Y1464567D02*
Y1378740D01*
G01X783465Y1468504D02*
G03X787402Y1472441I0J3937D01*
G01X783465Y1468504D02*
G03X787402Y1472441I0J3937D01*
G01X783465Y1468504D02*
X754724D01*
G01D02*
G03X750787Y1464567I0J-3937D01*
G01X783465Y1468504D02*
X754724D01*
G01D02*
G03X750787Y1464567I0J-3937D01*
G01X779528Y1476378D02*
X754724D01*
G01X779528D02*
X754724D01*
G01X787402Y1654331D02*
Y1472441D01*
G01X779528Y1596063D02*
Y1476378D01*
G01X787402Y1654331D02*
Y1472441D01*
G01X779528Y1596063D02*
Y1476378D01*
G01X787402Y1596063D02*
G03X779528I-3937J0D01*
G01X787402D02*
G03X779528I-3937J0D01*
G01X1216535Y1658268D02*
X791339D01*
G01D02*
G03X787402Y1654331I0J-3937D01*
G01X779528D02*
G03X775591Y1658268I-3937J0D01*
G01X1216535D02*
X791339D01*
G01D02*
G03X787402Y1654331I0J-3937D01*
G01X779528D02*
G03X775591Y1658268I-3937J0D01*
G01X779528Y1654331D02*
Y1626772D01*
G01D02*
G03X787402I3937J0D01*
G01X779528Y1654331D02*
Y1626772D01*
G01D02*
G03X787402I3937J0D01*
G01X806437Y277843D02*
G03X813362Y264712I37662J11471D01*
G01X806437Y277843D02*
G03X813362Y264712I37662J11471D01*
G01X806437Y750284D02*
G03X813362Y737153I37662J11471D01*
G01X806437Y750284D02*
G03X813362Y737154I37661J11472D01*
G01X866142Y-148819D02*
Y-11811D01*
G01Y-148819D02*
G03X870079Y-152756I3937J0D01*
G01X866142Y-11811D02*
Y-148819D01*
G01D02*
G03X870079Y-152756I3937J0D01*
G01X866142Y-129134D02*
G03X858268I-3937J0D01*
G01X866142D02*
G03X858268I-3937J0D01*
G01Y-148819D02*
Y-129134D01*
G01X854331Y-152756D02*
G03X858268Y-148819I0J3937D01*
G01D02*
Y-129134D01*
G01X854331Y-152756D02*
G03X858268Y-148819I0J3937D01*
G01X1177165Y-152756D02*
X870079D01*
G01D02*
X1177165D01*
G01X858268Y-98425D02*
Y-15748D01*
G01Y-98425D02*
Y-15748D01*
G01Y-98425D02*
G03X866142I3937J0D01*
G01X858268D02*
G03X866142I3937J0D01*
G01Y-11811D02*
G03X862205Y-7874I-3937J0D01*
G01X866142Y-11811D02*
G03X862205Y-7874I-3937J0D01*
G01X927032Y-57820D02*
G03X962731I17850J-12259D01*
G01X927032Y-57821D02*
G03X962732I17850J-12258D01*
G01X927032Y-57820D02*
G03X935199Y-42571I-64908J44575D01*
G01X954565D02*
G03X935199I-9683J-3885D01*
G01X927032Y-57821D02*
G03X935199Y-42571I-64909J44573D01*
G01X954564D02*
G03X935199I-9682J-3885D01*
G01X944512Y1089122D02*
G03X978323I16905J-13531D01*
G01X944512Y1089121D02*
G03X978323I16905J-13531D01*
G01X944512Y1431641D02*
G03X978323I16905J-13531D01*
G01X944512D02*
G03X978323I16905J-13531D01*
G01X954565Y-42571D02*
G03X962731Y-57820I73077J29322D01*
G01X954564Y-42570D02*
G03X962732Y-57821I73076J29324D01*
G01X971398Y1102252D02*
G03X978323Y1089122I37661J11472D01*
G01X971398Y1102252D02*
G03X978323Y1089121I37662J11471D01*
G01X971398Y1102252D02*
G03X951437I-9980J-3039D01*
G01X971398D02*
G03X951437I-9980J-3039D01*
G01X944512Y1089122D02*
G03X951437Y1102252I-30737J24602D01*
G01X944512Y1089121D02*
G03X951437Y1102252I-30737J24602D01*
G01X971398Y1444772D02*
G03X978323Y1431641I37662J11471D01*
G01X971398Y1444772D02*
G03X978323Y1431641I37662J11471D01*
G01X971398Y1444772D02*
G03X951437I-9980J-3040D01*
G01X944512Y1431641D02*
G03X951437Y1444772I-30737J24602D01*
G01X944512Y1431641D02*
G03X951437Y1444772I-30737J24602D01*
G01X971398D02*
G03X951437I-9980J-3039D01*
G01X1181102Y-148819D02*
Y-3937D01*
G01X1177165Y-152756D02*
G03X1181102Y-148819I0J3937D01*
G01X1177165Y-152756D02*
G03X1181102Y-148819I0J3937D01*
G01D02*
Y-3937D01*
G01Y-94488D02*
G03X1188976I3937J0D01*
G01X1181102D02*
G03X1188976I3937J0D01*
G01Y-125197D02*
G03X1181102I-3937J0D01*
G01X1188976D02*
G03X1181102I-3937J0D01*
G01X1185039Y0D02*
G03X1181102Y-3937I0J-3937D01*
G01X1185039Y0D02*
G03X1181102Y-3937I0J-3937D01*
G01X1164984Y557626D02*
G03X1198795I16906J-13531D01*
G01X1164984Y557625D02*
G03X1198795I16906J-13531D01*
G01X1191870Y570756D02*
G03X1171909I-9980J-3039D01*
G01X1191870D02*
G03X1171909I-9980J-3039D01*
G01X1164984Y557626D02*
G03X1171909Y570756I-30736J24602D01*
G01X1164984Y557625D02*
G03X1171909Y570756I-30737J24602D01*
G01X1164984Y971011D02*
G03X1198795I16906J-13531D01*
G01X1164984D02*
G03X1198795I16906J-13531D01*
G01X1191870Y984142D02*
G03X1171909I-9980J-3040D01*
G01X1191870D02*
G03X1171909I-9980J-3039D01*
G01X1164984Y971011D02*
G03X1171909Y984142I-30737J24602D01*
G01X1164984Y971011D02*
G03X1171909Y984142I-30737J24602D01*
G01X1164173Y1378740D02*
Y1468504D01*
G01X1930906Y1374803D02*
X1168110D01*
G01X1164173Y1378740D02*
G03X1168110Y1374803I3937J0D01*
G01X1172047Y1382677D02*
Y1464567D01*
G01X1195669Y1382677D02*
X1172047D01*
G01X1930906Y1374803D02*
X1168110D01*
G01X1164173Y1378740D02*
G03X1168110Y1374804I3937J1D01*
G01X1164173Y1378740D02*
Y1468504D01*
G01X1172047Y1382677D02*
Y1464567D01*
G01X1195669Y1382677D02*
X1172047D01*
G01X1168110Y1472441D02*
G03X1164173Y1468504I0J-3937D01*
G01X1168110Y1472441D02*
G03X1164173Y1468504I0J-3937D01*
G01X1172047Y1464567D02*
X1216535D01*
G01X1172047D02*
X1216535D01*
G01X1168110Y1472441D02*
X1216535D01*
G01X1168110D02*
X1216535D01*
G01X1164984Y1561563D02*
G03X1171909Y1574693I-30736J24602D01*
G01X1164984Y1561562D02*
G03X1171909Y1574693I-30737J24602D01*
G01X1164984Y1561563D02*
G03X1198795I16906J-13531D01*
G01X1164984Y1561562D02*
G03X1198795I16906J-13531D01*
G01X1191870Y1574693D02*
G03X1171909I-9980J-3039D01*
G01X1191870D02*
G03X1171909I-9980J-3039D01*
G01X1188976Y-148819D02*
Y-125197D01*
G01Y-148819D02*
G03X1192913Y-152756I3937J0D01*
G01X1188976Y-148819D02*
Y-125197D01*
G01Y-148819D02*
G03X1192913Y-152756I3937J0D01*
G01D02*
X1919843D01*
G01X1192913D02*
X1919843D01*
G01X1188976Y-94488D02*
Y-7874D01*
G01Y-94488D02*
Y-7874D01*
G01X1185039Y0D02*
X1366142D01*
G01X1188976Y-7874D02*
X1315748D01*
G01X1185039Y0D02*
X1366142D01*
G01X1188976Y-7874D02*
X1315748D01*
G01X1191870Y570756D02*
G03X1198795Y557626I37662J11472D01*
G01X1191870Y570756D02*
G03X1198795Y557626I37662J11472D01*
G01X1191870Y984142D02*
G03X1198795Y971011I37662J11471D01*
G01X1191870Y984142D02*
G03X1198795Y971011I37662J11471D01*
G01X1524606Y1382677D02*
X1226378D01*
G01X1524606D02*
X1226378D01*
G01X1195669Y1374803D02*
G03Y1382677I0J3937D01*
G01X1226378D02*
G03Y1374803I0J-3937D01*
G01X1195669D02*
G03Y1382677I0J3937D01*
G01X1226378D02*
G03Y1374803I0J-3937D01*
G01X1216535Y1464567D02*
G03X1228346Y1476378I0J11811D01*
G01X1216535Y1464567D02*
G03X1228346Y1476378I0J11811D01*
G01Y1592126D02*
Y1476378D01*
G01Y1592126D02*
Y1476378D01*
G01X1220472Y1654331D02*
Y1476378D01*
G01X1216535Y1472441D02*
G03X1220472Y1476378I0J3937D01*
G01X1216535Y1472441D02*
G03X1220472Y1476378I0J3937D01*
G01D02*
Y1654331D01*
G01X1191870Y1574693D02*
G03X1198795Y1561563I37662J11472D01*
G01X1191870Y1574693D02*
G03X1198795Y1561562I37662J11471D01*
G01X1228346Y1592126D02*
G03X1220472I-3937J0D01*
G01X1228346D02*
G03X1220472I-3937J0D01*
G01X1232283Y1658268D02*
X1442382D01*
G01X1232283D02*
G03X1228346Y1654331I0J-3937D01*
G01X1232283Y1658268D02*
X1442382D01*
G01X1232283D02*
G03X1228346Y1654331I0J-3937D01*
G01D02*
Y1622835D01*
G01Y1654331D02*
Y1622835D01*
G01X1220472Y1654331D02*
G03X1216535Y1658268I-3937J0D01*
G01X1220472Y1654331D02*
G03X1216535Y1658268I-3937J0D01*
G01X1220472Y1622835D02*
G03X1228346I3937J0D01*
G01X1220472D02*
G03X1228346I3937J0D01*
G01X1284965Y378885D02*
G03X1318776I16906J-13531D01*
G01X1284965D02*
G03X1318775I16905J-13531D01*
G01X1284965Y831641D02*
G03X1318776I16906J-13531D01*
G01X1284965D02*
G03X1318775I16905J-13531D01*
G01X1284965Y1284397D02*
G03X1318776I16906J-13531D01*
G01X1284965D02*
G03X1318775I16905J-13531D01*
G01X1315748Y-7874D02*
G03Y0I0J3937D01*
G01Y-7874D02*
G03Y0I0J3937D01*
G01X1311850Y392016D02*
G03X1291890I-9980J-3040D01*
G01X1311850D02*
G03X1318776Y378885I37662J11473D01*
G01X1311851Y392016D02*
G03X1291890I-9980J-3039D01*
G01X1311851D02*
G03X1318775Y378885I37663J11469D01*
G01X1284965D02*
G03X1291890Y392016I-30737J24602D01*
G01X1284965Y378885D02*
G03X1291890Y392016I-30737J24602D01*
G01X1284965Y831641D02*
G03X1291890Y844772I-30737J24602D01*
G01X1311850D02*
G03X1318776Y831641I37662J11473D01*
G01X1284965D02*
G03X1291890Y844772I-30737J24602D01*
G01X1311851D02*
G03X1318775Y831641I37663J11469D01*
G01X1311850Y844772D02*
G03X1291890I-9980J-3040D01*
G01X1311851D02*
G03X1291890I-9980J-3039D01*
G01X1284965Y1284397D02*
G03X1291890Y1297528I-30737J24602D01*
G01X1311850D02*
G03X1291890I-9980J-3040D01*
G01X1311850D02*
G03X1318776Y1284397I37661J11473D01*
G01X1284965D02*
G03X1291890Y1297528I-30737J24602D01*
G01X1311851D02*
G03X1291890I-9980J-3040D01*
G01X1311851D02*
G03X1318775Y1284397I37663J11469D01*
G01X1377953Y3937D02*
Y51181D01*
G01Y3937D02*
Y51181D01*
G01X1370079Y3937D02*
Y55118D01*
G01X1366142Y0D02*
G03X1370079Y3937I0J3937D01*
G01X1366142Y-7874D02*
G03X1377953Y3937I0J11811D01*
G01X1346457Y-7874D02*
X1366142D01*
G01Y0D02*
G03X1370079Y3937I0J3937D01*
G01D02*
Y55118D01*
G01X1346457Y-7874D02*
X1366142D01*
G01D02*
G03X1377953Y3937I0J11811D01*
G01X1346457Y0D02*
G03Y-7874I0J-3937D01*
G01Y0D02*
G03Y-7874I0J-3937D01*
G01X1374016Y59055D02*
G03X1370079Y55118I0J-3937D01*
G01X1374016Y59056D02*
G03X1370079Y55118I0J-3937D01*
G01X1374016Y59055D02*
X1555118D01*
G01X1377953Y51181D02*
X1551181D01*
G01X1374016Y59055D02*
X1555118D01*
G01X1377953Y51181D02*
X1551181D01*
G01X1442382Y1658268D02*
G03X1450256I3937J0D01*
G01X1442382D02*
G03X1450256I3937J0D01*
G01D02*
X1919843D01*
G01X1450256D02*
X1919843D01*
G01X1562992Y0D02*
X1930906D01*
G01X1559055Y55118D02*
Y3937D01*
G01D02*
G03X1562992Y0I3937J0D01*
G01Y-7874D02*
X1593701D01*
G01X1559055Y55118D02*
Y3937D01*
G01D02*
G03X1562992Y0I3937J0D01*
G01D02*
X1930906D01*
G01X1562992Y-7874D02*
X1593701D01*
G01X1551181Y51181D02*
Y3937D01*
G01D02*
G03X1562992Y-7874I11811J0D01*
G01X1551181Y51181D02*
Y3937D01*
G01D02*
G03X1562992Y-7874I11811J0D01*
G01X1559055Y55118D02*
G03X1555118Y59055I-3937J0D01*
G01X1559055Y55118D02*
G03X1555118Y59055I-3937J0D01*
G01X1532996Y378885D02*
G03X1566807I16906J-13531D01*
G01X1532996D02*
G03X1566807I16906J-13531D01*
G01X1559882Y392016D02*
G03X1566807Y378885I37662J11471D01*
G01X1559882Y392016D02*
G03X1566807Y378885I37662J11471D01*
G01X1559882Y392016D02*
G03X1539921I-9980J-3039D01*
G01X1559882D02*
G03X1539921I-9980J-3039D01*
G01X1532996Y378885D02*
G03X1539921Y392016I-30737J24602D01*
G01X1532996Y378885D02*
G03X1539921Y392016I-30737J24602D01*
G01X1559882Y844772D02*
G03X1566807Y831641I37662J11471D01*
G01X1559882Y844772D02*
G03X1566807Y831641I37662J11471D01*
G01X1532996D02*
G03X1539921Y844772I-30737J24602D01*
G01X1532996Y831641D02*
G03X1539921Y844772I-30737J24602D01*
G01X1532996Y831641D02*
G03X1566807I16906J-13531D01*
G01X1532996D02*
G03X1566807I16906J-13531D01*
G01X1559882Y844772D02*
G03X1539921I-9980J-3040D01*
G01X1559882D02*
G03X1539921I-9980J-3039D01*
G01X1532996Y1284397D02*
G03X1566807I16906J-13531D01*
G01X1532996D02*
G03X1566807I16906J-13531D01*
G01X1559882Y1297528D02*
G03X1566807Y1284397I37662J11471D01*
G01X1559882Y1297528D02*
G03X1566807Y1284397I37662J11471D01*
G01X1559882Y1297528D02*
G03X1539921I-9980J-3040D01*
G01X1532996Y1284397D02*
G03X1539921Y1297528I-30737J24602D01*
G01X1532996Y1284397D02*
G03X1539921Y1297528I-30737J24602D01*
G01X1559882D02*
G03X1539921I-9980J-3040D01*
G01X1563976Y1382677D02*
G03Y1374803I0J-3937D01*
G01Y1382677D02*
G03Y1374803I0J-3937D01*
G01X1524606D02*
G03Y1382677I0J3937D01*
G01Y1374803D02*
G03Y1382677I0J3937D01*
G01X1864567D02*
X1563976D01*
G01X1864567D02*
X1563976D01*
G01X1593701Y-7874D02*
G03Y0I0J3937D01*
G01Y-7874D02*
G03Y0I0J3937D01*
G01X1633071D02*
G03Y-7874I0J-3937D01*
G01D02*
X1880512D01*
G01X1633071D02*
X1880512D01*
G01X1633071Y0D02*
G03Y-7874I0J-3937D01*
G01X1693996Y829921D02*
G03X1653839I-20078J0D01*
G01X1693996D02*
G03I-20079J0D01*
G01X1653839D02*
G03X1693996I20078J0D01*
G01X1781028Y378885D02*
G03X1814839I16906J-13531D01*
G01X1781028D02*
G03X1814838I16905J-13531D01*
G01X1807913Y392016D02*
G03X1814839Y378885I37662J11473D01*
G01X1807914Y392016D02*
G03X1814838Y378885I37663J11469D01*
G01X1807913Y392016D02*
G03X1787953I-9980J-3040D01*
G01X1807914D02*
G03X1787953I-9980J-3039D01*
G01X1781028Y378885D02*
G03X1787953Y392016I-30737J24602D01*
G01X1781028Y378885D02*
G03X1787953Y392016I-30737J24602D01*
G01X1807913Y844772D02*
G03X1814839Y831641I37662J11473D01*
G01X1807914Y844772D02*
G03X1814838Y831641I37663J11469D01*
G01X1781028D02*
G03X1787953Y844772I-30737J24602D01*
G01X1781028Y831641D02*
G03X1787953Y844772I-30737J24602D01*
G01X1781028Y831641D02*
G03X1814839I16906J-13531D01*
G01X1781028D02*
G03X1814838I16905J-13531D01*
G01X1807913Y844772D02*
G03X1787953I-9980J-3040D01*
G01X1807914D02*
G03X1787953I-9980J-3039D01*
G01X1781028Y1284397D02*
G03X1814839I16906J-13531D01*
G01X1781028D02*
G03X1814838I16905J-13531D01*
G01X1807913Y1297528D02*
G03X1814839Y1284397I37661J11473D01*
G01X1807914Y1297528D02*
G03X1814838Y1284397I37663J11469D01*
G01X1807913Y1297528D02*
G03X1787953I-9980J-3040D01*
G01X1781028Y1284397D02*
G03X1787953Y1297528I-30737J24602D01*
G01X1781028Y1284397D02*
G03X1787953Y1297528I-30737J24602D01*
G01X1807914D02*
G03X1787953I-9980J-3040D01*
G01X1911220Y0D02*
G03Y-7874I0J-3937D01*
G01Y0D02*
G03Y-7874I0J-3937D01*
G01X1880512D02*
G03Y0I0J3937D01*
G01Y-7874D02*
G03Y0I0J3937D01*
G01X1930906Y1382677D02*
X1895276D01*
G01D02*
G03Y1374803I0J-3937D01*
G01X1930906Y1382677D02*
X1895276D01*
G01D02*
G03Y1374803I0J-3937D01*
G01X1864567D02*
G03Y1382677I0J3937D01*
G01Y1374803D02*
G03Y1382677I0J3937D01*
G01X1919843Y-152756D02*
G03X1934843Y-137756I0J15000D01*
G01X1919843Y-152756D02*
G03X1934843Y-137756I0J15000D01*
G01Y-11811D02*
Y-137756D01*
G01Y-11811D02*
Y-137756D01*
G01X1930906Y0D02*
G03X1934843Y3937I0J3937D01*
G01X1930906Y0D02*
G03X1934843Y3937I0J3937D01*
G01Y-11811D02*
G03X1930906Y-7874I-3937J0D01*
G01X1934843Y-11811D02*
G03X1930906Y-7874I-3937J0D01*
G01X1911220D02*
X1930906D01*
G01X1911220D02*
X1930906D01*
G01X1934843Y1370866D02*
Y3937D01*
G01D02*
Y1370866D01*
G01D02*
G03X1930906Y1374803I-3937J0D01*
G01X1934843Y1370866D02*
G03X1930906Y1374803I-3937J0D01*
G01Y1382677D02*
G03X1934843Y1386614I0J3937D01*
G01X1930906Y1382677D02*
G03X1934843Y1386614I0J3937D01*
G01D02*
Y1643268D01*
G01Y1386614D02*
Y1643268D01*
G01D02*
G03X1919843Y1658268I-15000J0D01*
G01X1934843Y1643268D02*
G03X1919843Y1658268I-15000J0D01*
G54D28*
X129000Y997700D03*
X195500Y585700D03*
X749383Y915989D03*
X855400Y458500D03*
X1429400Y558100D03*
Y562100D03*
X1770800Y1009700D03*
X1886450Y880323D03*
X1900200Y938000D03*
Y921000D03*
Y925000D03*
G54D55*
X854849Y423076D03*
X879649D03*
X1041380Y421129D03*
X1066180D03*
X1841693Y839032D03*
X1905593D03*
X1880793D03*
X1866493D03*
G54D46*
X729898Y882446D03*
X731866D03*
Y894558D03*
X729898D03*
G54D19*
X90793Y981195D03*
X157493Y569195D03*
X746383Y920289D03*
X1730911Y1002024D03*
X1830266Y907899D03*
X1856200Y965000D03*
X1881920Y874918D03*
G54D37*
X694613Y593113D03*
Y621397D03*
G54D29*
X125600Y997700D03*
X192100Y585700D03*
X745983Y915989D03*
X852000Y458500D03*
X1426000Y558100D03*
Y562100D03*
X1767400Y1009700D03*
X1883050Y880323D03*
X1896800Y938000D03*
Y921000D03*
Y925000D03*
G54D38*
X711711Y881500D03*
X743200Y874600D03*
X729182Y862502D03*
X874900Y471600D03*
X872000Y484300D03*
X856900Y484500D03*
X866100Y484400D03*
X1888000Y887300D03*
X1889500Y905800D03*
X1892443Y897550D03*
G54D47*
X722419Y865905D03*
X1887726Y917859D03*
G54D56*
X874800Y467500D03*
X850100Y473300D03*
X1436200Y561900D03*
X1893500Y909300D03*
G54D57*
X874800Y463900D03*
X850100Y469700D03*
X1436200Y558300D03*
X1893500Y905700D03*
G54D48*
X719719Y865905D03*
X1885026Y917859D03*
G54D39*
X711711Y884900D03*
X743200Y878000D03*
X729182Y865902D03*
X874900Y475000D03*
X872000Y487700D03*
X856900Y487900D03*
X866100Y487800D03*
X1889500Y909200D03*
X1892443Y900950D03*
X1888000Y890700D03*
G54D58*
X866100Y468545D03*
Y470515D03*
Y472485D03*
Y474455D03*
X856900D03*
Y472485D03*
Y470515D03*
Y468545D03*
G54D49*
X719119Y858953D03*
X1898000Y888500D03*
G54D59*
X1358858Y596400D03*
X1387142D03*
M02*
